FILE_TYPE = MACRO_DRAWING;
SET COLOR_WIRE YELLOW;
SET COLOR_PROP ORANGE;
SET COLOR_DOT WHITE;
SET COLOR_ARC YELLOW;
SET COLOR_BODY GREEN;
SET COLOR_NOTE PURPLE;
SET PROP_DISPLAY VALUE;
SET PAGE_NUMBER P52;
FORCEADD OFFPAGE..2
R 2
(-1975 -125);
FORCEPROP 2 LAST $XR1 101 
J 0
(-2350 -125);
DISPLAY 0.638298 (-2350 -125);
PAINT MONO (-2350 -125);
FORCEPROP 2 LAST $XR0 100 
J 0
(-2230 -125);
DISPLAY 0.638298 (-2230 -125);
PAINT MONO (-2230 -125);
FORCEPROP 2 LAST CDS_LIB standard
J 0
(-1975 -125);
PAINT MONO (-1975 -125);
DISPLAY INVISIBLE (-1975 -125);
FORCEPROP 1 LAST OFFPAGE TRUE
J 2
(-2300 -250);
DISPLAY 0.872340 (-2300 -250);
DISPLAY INVISIBLE (-2300 -250);
FORCEPROP 1 LAST COMMENT_BODY TRUE
J 2
(-1930 -220);
DISPLAY 0.872340 (-1930 -220);
PAINT GREEN (-1930 -220);
DISPLAY INVISIBLE (-1930 -220);
FORCEPROP 2 LAST PATH I1
J 0
(-1925 -50);
DISPLAY 1.021277 (-1925 -50);
DISPLAY INVISIBLE (-1925 -50);
FORCEADD TAP..1
R 2
(-950 -50);
FORCEPROP 3 LASTPIN (-900 -50) SIG_NAME M_B_CPU1_SB_CB<0>
J 0
(-890 -40);
DISPLAY 0.659574 (-890 -40);
PAINT MONO (-890 -40);
DISPLAY INVISIBLE (-890 -40);
FORCEPROP 1 LASTPIN (-900 -50) BN 0
J 2
(-888 -42);
DISPLAY 0.680851 (-888 -42);
PAINT GREEN (-888 -42);
FORCEPROP 2 LAST CDS_LIB standard
J 0
(-950 -50);
DISPLAY INVISIBLE (-950 -50);
FORCEPROP 1 LAST BODY_TYPE PLUMBING
J 2
(-950 0);
DISPLAY 0.872340 (-950 0);
PAINT GREEN (-950 0);
DISPLAY INVISIBLE (-950 0);
FORCEPROP 1 LAST HDL_TAP TRUE
J 2
(-1275 -175);
DISPLAY 0.872340 (-1275 -175);
DISPLAY INVISIBLE (-1275 -175);
FORCEPROP 1 LAST PATH I10
J 2
(-948 -50);
DISPLAY 0.872340 (-948 -50);
PAINT GREEN (-948 -50);
DISPLAY INVISIBLE (-948 -50);
FORCEADD TAP..1
(2475 450);
FORCEPROP 3 LASTPIN (2425 450) SIG_NAME M_B_CPU1_SA_CS_N<0>
J 0
(2435 460);
DISPLAY 0.659574 (2435 460);
PAINT MONO (2435 460);
DISPLAY INVISIBLE (2435 460);
FORCEPROP 1 LASTPIN (2425 450) BN 0
J 0
(2413 458);
DISPLAY 0.680851 (2413 458);
PAINT GREEN (2413 458);
FORCEPROP 2 LAST CDS_LIB standard
J 0
(2475 450);
DISPLAY INVISIBLE (2475 450);
FORCEPROP 1 LAST BODY_TYPE PLUMBING
J 0
(2475 500);
DISPLAY 0.872340 (2475 500);
PAINT GREEN (2475 500);
DISPLAY INVISIBLE (2475 500);
FORCEPROP 1 LAST HDL_TAP TRUE
J 0
(2800 325);
DISPLAY 0.872340 (2800 325);
DISPLAY INVISIBLE (2800 325);
FORCEPROP 1 LAST PATH I100
J 0
(2473 450);
DISPLAY 0.872340 (2473 450);
PAINT GREEN (2473 450);
DISPLAY INVISIBLE (2473 450);
FORCEADD TAP..1
(2475 550);
FORCEPROP 3 LASTPIN (2425 550) SIG_NAME M_B_CPU1_SA_CS_N<2>
J 0
(2435 560);
DISPLAY 0.659574 (2435 560);
PAINT MONO (2435 560);
DISPLAY INVISIBLE (2435 560);
FORCEPROP 1 LASTPIN (2425 550) BN 2
J 0
(2413 558);
DISPLAY 0.680851 (2413 558);
PAINT GREEN (2413 558);
FORCEPROP 2 LAST CDS_LIB standard
J 0
(2475 550);
DISPLAY INVISIBLE (2475 550);
FORCEPROP 1 LAST BODY_TYPE PLUMBING
J 0
(2475 600);
DISPLAY 0.872340 (2475 600);
PAINT GREEN (2475 600);
DISPLAY INVISIBLE (2475 600);
FORCEPROP 1 LAST HDL_TAP TRUE
J 0
(2800 425);
DISPLAY 0.872340 (2800 425);
DISPLAY INVISIBLE (2800 425);
FORCEPROP 1 LAST PATH I101
J 0
(2473 550);
DISPLAY 0.872340 (2473 550);
PAINT GREEN (2473 550);
DISPLAY INVISIBLE (2473 550);
FORCEADD TAP..1
(2475 500);
FORCEPROP 3 LASTPIN (2425 500) SIG_NAME M_B_CPU1_SA_CS_N<1>
J 0
(2435 510);
DISPLAY 0.659574 (2435 510);
PAINT MONO (2435 510);
DISPLAY INVISIBLE (2435 510);
FORCEPROP 1 LASTPIN (2425 500) BN 1
J 0
(2413 508);
DISPLAY 0.680851 (2413 508);
PAINT GREEN (2413 508);
FORCEPROP 2 LAST CDS_LIB standard
J 0
(2475 500);
DISPLAY INVISIBLE (2475 500);
FORCEPROP 1 LAST BODY_TYPE PLUMBING
J 0
(2475 550);
DISPLAY 0.872340 (2475 550);
PAINT GREEN (2475 550);
DISPLAY INVISIBLE (2475 550);
FORCEPROP 1 LAST HDL_TAP TRUE
J 0
(2800 375);
DISPLAY 0.872340 (2800 375);
DISPLAY INVISIBLE (2800 375);
FORCEPROP 1 LAST PATH I102
J 0
(2473 500);
DISPLAY 0.872340 (2473 500);
PAINT GREEN (2473 500);
DISPLAY INVISIBLE (2473 500);
FORCEADD TAP..1
(2475 600);
FORCEPROP 3 LASTPIN (2425 600) SIG_NAME M_B_CPU1_SA_CS_N<3>
J 0
(2435 610);
DISPLAY 0.659574 (2435 610);
PAINT MONO (2435 610);
DISPLAY INVISIBLE (2435 610);
FORCEPROP 1 LASTPIN (2425 600) BN 3
J 0
(2413 608);
DISPLAY 0.680851 (2413 608);
PAINT GREEN (2413 608);
FORCEPROP 2 LAST CDS_LIB standard
J 0
(2475 600);
DISPLAY INVISIBLE (2475 600);
FORCEPROP 1 LAST BODY_TYPE PLUMBING
J 0
(2475 650);
DISPLAY 0.872340 (2475 650);
PAINT GREEN (2475 650);
DISPLAY INVISIBLE (2475 650);
FORCEPROP 1 LAST HDL_TAP TRUE
J 0
(2800 475);
DISPLAY 0.872340 (2800 475);
DISPLAY INVISIBLE (2800 475);
FORCEPROP 1 LAST PATH I103
J 0
(2473 600);
DISPLAY 0.872340 (2473 600);
PAINT GREEN (2473 600);
DISPLAY INVISIBLE (2473 600);
FORCEADD TAP..1
(2475 850);
FORCEPROP 3 LASTPIN (2425 850) SIG_NAME M_B_CPU1_SB_CA<1>
J 0
(2435 860);
DISPLAY 0.659574 (2435 860);
PAINT MONO (2435 860);
DISPLAY INVISIBLE (2435 860);
FORCEPROP 1 LASTPIN (2425 850) BN 1
J 0
(2413 858);
DISPLAY 0.680851 (2413 858);
PAINT GREEN (2413 858);
FORCEPROP 2 LAST CDS_LIB standard
J 0
(2475 850);
DISPLAY INVISIBLE (2475 850);
FORCEPROP 1 LAST BODY_TYPE PLUMBING
J 0
(2475 900);
DISPLAY 0.872340 (2475 900);
PAINT GREEN (2475 900);
DISPLAY INVISIBLE (2475 900);
FORCEPROP 1 LAST HDL_TAP TRUE
J 0
(2800 725);
DISPLAY 0.872340 (2800 725);
DISPLAY INVISIBLE (2800 725);
FORCEPROP 1 LAST PATH I104
J 0
(2473 850);
DISPLAY 0.872340 (2473 850);
PAINT GREEN (2473 850);
DISPLAY INVISIBLE (2473 850);
FORCEADD TAP..1
(2475 800);
FORCEPROP 3 LASTPIN (2425 800) SIG_NAME M_B_CPU1_SB_CA<0>
J 0
(2435 810);
DISPLAY 0.659574 (2435 810);
PAINT MONO (2435 810);
DISPLAY INVISIBLE (2435 810);
FORCEPROP 1 LASTPIN (2425 800) BN 0
J 0
(2413 808);
DISPLAY 0.680851 (2413 808);
PAINT GREEN (2413 808);
FORCEPROP 2 LAST CDS_LIB standard
J 0
(2475 800);
DISPLAY INVISIBLE (2475 800);
FORCEPROP 1 LAST BODY_TYPE PLUMBING
J 0
(2475 850);
DISPLAY 0.872340 (2475 850);
PAINT GREEN (2475 850);
DISPLAY INVISIBLE (2475 850);
FORCEPROP 1 LAST HDL_TAP TRUE
J 0
(2800 675);
DISPLAY 0.872340 (2800 675);
DISPLAY INVISIBLE (2800 675);
FORCEPROP 1 LAST PATH I105
J 0
(2473 800);
DISPLAY 0.872340 (2473 800);
PAINT GREEN (2473 800);
DISPLAY INVISIBLE (2473 800);
FORCEADD TAP..1
(2475 900);
FORCEPROP 3 LASTPIN (2425 900) SIG_NAME M_B_CPU1_SB_CA<2>
J 0
(2435 910);
DISPLAY 0.659574 (2435 910);
PAINT MONO (2435 910);
DISPLAY INVISIBLE (2435 910);
FORCEPROP 1 LASTPIN (2425 900) BN 2
J 0
(2413 908);
DISPLAY 0.680851 (2413 908);
PAINT GREEN (2413 908);
FORCEPROP 2 LAST CDS_LIB standard
J 0
(2475 900);
DISPLAY INVISIBLE (2475 900);
FORCEPROP 1 LAST BODY_TYPE PLUMBING
J 0
(2475 950);
DISPLAY 0.872340 (2475 950);
PAINT GREEN (2475 950);
DISPLAY INVISIBLE (2475 950);
FORCEPROP 1 LAST HDL_TAP TRUE
J 0
(2800 775);
DISPLAY 0.872340 (2800 775);
DISPLAY INVISIBLE (2800 775);
FORCEPROP 1 LAST PATH I106
J 0
(2473 900);
DISPLAY 0.872340 (2473 900);
PAINT GREEN (2473 900);
DISPLAY INVISIBLE (2473 900);
FORCEADD TAP..1
(2475 1100);
FORCEPROP 3 LASTPIN (2425 1100) SIG_NAME M_B_CPU1_SB_CA<6>
J 0
(2435 1110);
DISPLAY 0.659574 (2435 1110);
PAINT MONO (2435 1110);
DISPLAY INVISIBLE (2435 1110);
FORCEPROP 1 LASTPIN (2425 1100) BN 6
J 0
(2413 1108);
DISPLAY 0.680851 (2413 1108);
PAINT GREEN (2413 1108);
FORCEPROP 2 LAST CDS_LIB standard
J 0
(2475 1100);
DISPLAY INVISIBLE (2475 1100);
FORCEPROP 1 LAST BODY_TYPE PLUMBING
J 0
(2475 1150);
DISPLAY 0.872340 (2475 1150);
PAINT GREEN (2475 1150);
DISPLAY INVISIBLE (2475 1150);
FORCEPROP 1 LAST HDL_TAP TRUE
J 0
(2800 975);
DISPLAY 0.872340 (2800 975);
DISPLAY INVISIBLE (2800 975);
FORCEPROP 1 LAST PATH I107
J 0
(2473 1100);
DISPLAY 0.872340 (2473 1100);
PAINT GREEN (2473 1100);
DISPLAY INVISIBLE (2473 1100);
FORCEADD TAP..1
(2475 1050);
FORCEPROP 3 LASTPIN (2425 1050) SIG_NAME M_B_CPU1_SB_CA<5>
J 0
(2435 1060);
DISPLAY 0.659574 (2435 1060);
PAINT MONO (2435 1060);
DISPLAY INVISIBLE (2435 1060);
FORCEPROP 1 LASTPIN (2425 1050) BN 5
J 0
(2413 1058);
DISPLAY 0.680851 (2413 1058);
PAINT GREEN (2413 1058);
FORCEPROP 2 LAST CDS_LIB standard
J 0
(2475 1050);
DISPLAY INVISIBLE (2475 1050);
FORCEPROP 1 LAST BODY_TYPE PLUMBING
J 0
(2475 1100);
DISPLAY 0.872340 (2475 1100);
PAINT GREEN (2475 1100);
DISPLAY INVISIBLE (2475 1100);
FORCEPROP 1 LAST HDL_TAP TRUE
J 0
(2800 925);
DISPLAY 0.872340 (2800 925);
DISPLAY INVISIBLE (2800 925);
FORCEPROP 1 LAST PATH I108
J 0
(2473 1050);
DISPLAY 0.872340 (2473 1050);
PAINT GREEN (2473 1050);
DISPLAY INVISIBLE (2473 1050);
FORCEADD TAP..1
(2475 1000);
FORCEPROP 3 LASTPIN (2425 1000) SIG_NAME M_B_CPU1_SB_CA<4>
J 0
(2435 1010);
DISPLAY 0.659574 (2435 1010);
PAINT MONO (2435 1010);
DISPLAY INVISIBLE (2435 1010);
FORCEPROP 1 LASTPIN (2425 1000) BN 4
J 0
(2413 1008);
DISPLAY 0.680851 (2413 1008);
PAINT GREEN (2413 1008);
FORCEPROP 2 LAST CDS_LIB standard
J 0
(2475 1000);
DISPLAY INVISIBLE (2475 1000);
FORCEPROP 1 LAST BODY_TYPE PLUMBING
J 0
(2475 1050);
DISPLAY 0.872340 (2475 1050);
PAINT GREEN (2475 1050);
DISPLAY INVISIBLE (2475 1050);
FORCEPROP 1 LAST HDL_TAP TRUE
J 0
(2800 875);
DISPLAY 0.872340 (2800 875);
DISPLAY INVISIBLE (2800 875);
FORCEPROP 1 LAST PATH I109
J 0
(2473 1000);
DISPLAY 0.872340 (2473 1000);
PAINT GREEN (2473 1000);
DISPLAY INVISIBLE (2473 1000);
FORCEADD TAP..1
R 2
(-950 50);
FORCEPROP 3 LASTPIN (-900 50) SIG_NAME M_B_CPU1_SB_CB<2>
J 0
(-890 60);
DISPLAY 0.659574 (-890 60);
PAINT MONO (-890 60);
DISPLAY INVISIBLE (-890 60);
FORCEPROP 1 LASTPIN (-900 50) BN 2
J 2
(-888 58);
DISPLAY 0.680851 (-888 58);
PAINT GREEN (-888 58);
FORCEPROP 2 LAST CDS_LIB standard
J 0
(-950 50);
DISPLAY INVISIBLE (-950 50);
FORCEPROP 1 LAST BODY_TYPE PLUMBING
J 2
(-950 100);
DISPLAY 0.872340 (-950 100);
PAINT GREEN (-950 100);
DISPLAY INVISIBLE (-950 100);
FORCEPROP 1 LAST HDL_TAP TRUE
J 2
(-1275 -75);
DISPLAY 0.872340 (-1275 -75);
DISPLAY INVISIBLE (-1275 -75);
FORCEPROP 1 LAST PATH I11
J 2
(-948 50);
DISPLAY 0.872340 (-948 50);
PAINT GREEN (-948 50);
DISPLAY INVISIBLE (-948 50);
FORCEADD TAP..1
(2475 950);
FORCEPROP 3 LASTPIN (2425 950) SIG_NAME M_B_CPU1_SB_CA<3>
J 0
(2435 960);
DISPLAY 0.659574 (2435 960);
PAINT MONO (2435 960);
DISPLAY INVISIBLE (2435 960);
FORCEPROP 1 LASTPIN (2425 950) BN 3
J 0
(2413 958);
DISPLAY 0.680851 (2413 958);
PAINT GREEN (2413 958);
FORCEPROP 2 LAST CDS_LIB standard
J 0
(2475 950);
DISPLAY INVISIBLE (2475 950);
FORCEPROP 1 LAST BODY_TYPE PLUMBING
J 0
(2475 1000);
DISPLAY 0.872340 (2475 1000);
PAINT GREEN (2475 1000);
DISPLAY INVISIBLE (2475 1000);
FORCEPROP 1 LAST HDL_TAP TRUE
J 0
(2800 825);
DISPLAY 0.872340 (2800 825);
DISPLAY INVISIBLE (2800 825);
FORCEPROP 1 LAST PATH I110
J 0
(2473 950);
DISPLAY 0.872340 (2473 950);
PAINT GREEN (2473 950);
DISPLAY INVISIBLE (2473 950);
FORCEADD TAP..1
(2475 1350);
FORCEPROP 3 LASTPIN (2425 1350) SIG_NAME M_B_CPU1_SA_CA<1>
J 0
(2435 1360);
DISPLAY 0.659574 (2435 1360);
PAINT MONO (2435 1360);
DISPLAY INVISIBLE (2435 1360);
FORCEPROP 1 LASTPIN (2425 1350) BN 1
J 0
(2413 1358);
DISPLAY 0.680851 (2413 1358);
PAINT GREEN (2413 1358);
FORCEPROP 2 LAST CDS_LIB standard
J 0
(2475 1350);
DISPLAY INVISIBLE (2475 1350);
FORCEPROP 1 LAST BODY_TYPE PLUMBING
J 0
(2475 1400);
DISPLAY 0.872340 (2475 1400);
PAINT GREEN (2475 1400);
DISPLAY INVISIBLE (2475 1400);
FORCEPROP 1 LAST HDL_TAP TRUE
J 0
(2800 1225);
DISPLAY 0.872340 (2800 1225);
DISPLAY INVISIBLE (2800 1225);
FORCEPROP 1 LAST PATH I111
J 0
(2473 1350);
DISPLAY 0.872340 (2473 1350);
PAINT GREEN (2473 1350);
DISPLAY INVISIBLE (2473 1350);
FORCEADD TAP..1
(2475 1400);
FORCEPROP 3 LASTPIN (2425 1400) SIG_NAME M_B_CPU1_SA_CA<2>
J 0
(2435 1410);
DISPLAY 0.659574 (2435 1410);
PAINT MONO (2435 1410);
DISPLAY INVISIBLE (2435 1410);
FORCEPROP 1 LASTPIN (2425 1400) BN 2
J 0
(2413 1408);
DISPLAY 0.680851 (2413 1408);
PAINT GREEN (2413 1408);
FORCEPROP 2 LAST CDS_LIB standard
J 0
(2475 1400);
DISPLAY INVISIBLE (2475 1400);
FORCEPROP 1 LAST BODY_TYPE PLUMBING
J 0
(2475 1450);
DISPLAY 0.872340 (2475 1450);
PAINT GREEN (2475 1450);
DISPLAY INVISIBLE (2475 1450);
FORCEPROP 1 LAST HDL_TAP TRUE
J 0
(2800 1275);
DISPLAY 0.872340 (2800 1275);
DISPLAY INVISIBLE (2800 1275);
FORCEPROP 1 LAST PATH I112
J 0
(2473 1400);
DISPLAY 0.872340 (2473 1400);
PAINT GREEN (2473 1400);
DISPLAY INVISIBLE (2473 1400);
FORCEADD TAP..1
(2475 1450);
FORCEPROP 3 LASTPIN (2425 1450) SIG_NAME M_B_CPU1_SA_CA<3>
J 0
(2435 1460);
DISPLAY 0.659574 (2435 1460);
PAINT MONO (2435 1460);
DISPLAY INVISIBLE (2435 1460);
FORCEPROP 1 LASTPIN (2425 1450) BN 3
J 0
(2413 1458);
DISPLAY 0.680851 (2413 1458);
PAINT GREEN (2413 1458);
FORCEPROP 2 LAST CDS_LIB standard
J 0
(2475 1450);
DISPLAY INVISIBLE (2475 1450);
FORCEPROP 1 LAST BODY_TYPE PLUMBING
J 0
(2475 1500);
DISPLAY 0.872340 (2475 1500);
PAINT GREEN (2475 1500);
DISPLAY INVISIBLE (2475 1500);
FORCEPROP 1 LAST HDL_TAP TRUE
J 0
(2800 1325);
DISPLAY 0.872340 (2800 1325);
DISPLAY INVISIBLE (2800 1325);
FORCEPROP 1 LAST PATH I113
J 0
(2473 1450);
DISPLAY 0.872340 (2473 1450);
PAINT GREEN (2473 1450);
DISPLAY INVISIBLE (2473 1450);
FORCEADD TAP..1
(2475 1300);
FORCEPROP 3 LASTPIN (2425 1300) SIG_NAME M_B_CPU1_SA_CA<0>
J 0
(2435 1310);
DISPLAY 0.659574 (2435 1310);
PAINT MONO (2435 1310);
DISPLAY INVISIBLE (2435 1310);
FORCEPROP 1 LASTPIN (2425 1300) BN 0
J 0
(2413 1308);
DISPLAY 0.680851 (2413 1308);
PAINT GREEN (2413 1308);
FORCEPROP 2 LAST CDS_LIB standard
J 0
(2475 1300);
DISPLAY INVISIBLE (2475 1300);
FORCEPROP 1 LAST BODY_TYPE PLUMBING
J 0
(2475 1350);
DISPLAY 0.872340 (2475 1350);
PAINT GREEN (2475 1350);
DISPLAY INVISIBLE (2475 1350);
FORCEPROP 1 LAST HDL_TAP TRUE
J 0
(2800 1175);
DISPLAY 0.872340 (2800 1175);
DISPLAY INVISIBLE (2800 1175);
FORCEPROP 1 LAST PATH I114
J 0
(2473 1300);
DISPLAY 0.872340 (2473 1300);
PAINT GREEN (2473 1300);
DISPLAY INVISIBLE (2473 1300);
FORCEADD TAP..1
(2475 1500);
FORCEPROP 3 LASTPIN (2425 1500) SIG_NAME M_B_CPU1_SA_CA<4>
J 0
(2435 1510);
DISPLAY 0.659574 (2435 1510);
PAINT MONO (2435 1510);
DISPLAY INVISIBLE (2435 1510);
FORCEPROP 1 LASTPIN (2425 1500) BN 4
J 0
(2413 1508);
DISPLAY 0.680851 (2413 1508);
PAINT GREEN (2413 1508);
FORCEPROP 2 LAST CDS_LIB standard
J 0
(2475 1500);
DISPLAY INVISIBLE (2475 1500);
FORCEPROP 1 LAST BODY_TYPE PLUMBING
J 0
(2475 1550);
DISPLAY 0.872340 (2475 1550);
PAINT GREEN (2475 1550);
DISPLAY INVISIBLE (2475 1550);
FORCEPROP 1 LAST HDL_TAP TRUE
J 0
(2800 1375);
DISPLAY 0.872340 (2800 1375);
DISPLAY INVISIBLE (2800 1375);
FORCEPROP 1 LAST PATH I115
J 0
(2473 1500);
DISPLAY 0.872340 (2473 1500);
PAINT GREEN (2473 1500);
DISPLAY INVISIBLE (2473 1500);
FORCEADD TAP..1
(2475 1600);
FORCEPROP 3 LASTPIN (2425 1600) SIG_NAME M_B_CPU1_SA_CA<6>
J 0
(2435 1610);
DISPLAY 0.659574 (2435 1610);
PAINT MONO (2435 1610);
DISPLAY INVISIBLE (2435 1610);
FORCEPROP 1 LASTPIN (2425 1600) BN 6
J 0
(2413 1608);
DISPLAY 0.680851 (2413 1608);
PAINT GREEN (2413 1608);
FORCEPROP 2 LAST CDS_LIB standard
J 0
(2475 1600);
DISPLAY INVISIBLE (2475 1600);
FORCEPROP 1 LAST BODY_TYPE PLUMBING
J 0
(2475 1650);
DISPLAY 0.872340 (2475 1650);
PAINT GREEN (2475 1650);
DISPLAY INVISIBLE (2475 1650);
FORCEPROP 1 LAST HDL_TAP TRUE
J 0
(2800 1475);
DISPLAY 0.872340 (2800 1475);
DISPLAY INVISIBLE (2800 1475);
FORCEPROP 1 LAST PATH I116
J 0
(2473 1600);
DISPLAY 0.872340 (2473 1600);
PAINT GREEN (2473 1600);
DISPLAY INVISIBLE (2473 1600);
FORCEADD TAP..1
(2475 1550);
FORCEPROP 3 LASTPIN (2425 1550) SIG_NAME M_B_CPU1_SA_CA<5>
J 0
(2435 1560);
DISPLAY 0.659574 (2435 1560);
PAINT MONO (2435 1560);
DISPLAY INVISIBLE (2435 1560);
FORCEPROP 1 LASTPIN (2425 1550) BN 5
J 0
(2413 1558);
DISPLAY 0.680851 (2413 1558);
PAINT GREEN (2413 1558);
FORCEPROP 2 LAST CDS_LIB standard
J 0
(2475 1550);
DISPLAY INVISIBLE (2475 1550);
FORCEPROP 1 LAST BODY_TYPE PLUMBING
J 0
(2475 1600);
DISPLAY 0.872340 (2475 1600);
PAINT GREEN (2475 1600);
DISPLAY INVISIBLE (2475 1600);
FORCEPROP 1 LAST HDL_TAP TRUE
J 0
(2800 1425);
DISPLAY 0.872340 (2800 1425);
DISPLAY INVISIBLE (2800 1425);
FORCEPROP 1 LAST PATH I117
J 0
(2473 1550);
DISPLAY 0.872340 (2473 1550);
PAINT GREEN (2473 1550);
DISPLAY INVISIBLE (2473 1550);
FORCEADD TAP..1
(2475 1800);
FORCEPROP 3 LASTPIN (2425 1800) SIG_NAME M_B_CPU1_SB_DQS_DN<1>
J 0
(2435 1810);
DISPLAY 0.659574 (2435 1810);
PAINT MONO (2435 1810);
DISPLAY INVISIBLE (2435 1810);
FORCEPROP 1 LASTPIN (2425 1800) BN 1
J 0
(2413 1808);
DISPLAY 0.680851 (2413 1808);
PAINT GREEN (2413 1808);
FORCEPROP 2 LAST CDS_LIB standard
J 0
(2475 1800);
DISPLAY INVISIBLE (2475 1800);
FORCEPROP 1 LAST BODY_TYPE PLUMBING
J 0
(2475 1850);
DISPLAY 0.872340 (2475 1850);
PAINT GREEN (2475 1850);
DISPLAY INVISIBLE (2475 1850);
FORCEPROP 1 LAST HDL_TAP TRUE
J 0
(2800 1675);
DISPLAY 0.872340 (2800 1675);
DISPLAY INVISIBLE (2800 1675);
FORCEPROP 1 LAST PATH I118
J 0
(2473 1800);
DISPLAY 0.872340 (2473 1800);
PAINT GREEN (2473 1800);
DISPLAY INVISIBLE (2473 1800);
FORCEADD TAP..1
(2475 1950);
FORCEPROP 3 LASTPIN (2425 1950) SIG_NAME M_B_CPU1_SB_DQS_DN<4>
J 0
(2435 1960);
DISPLAY 0.659574 (2435 1960);
PAINT MONO (2435 1960);
DISPLAY INVISIBLE (2435 1960);
FORCEPROP 1 LASTPIN (2425 1950) BN 4
J 0
(2413 1958);
DISPLAY 0.680851 (2413 1958);
PAINT GREEN (2413 1958);
FORCEPROP 2 LAST CDS_LIB standard
J 0
(2475 1950);
DISPLAY INVISIBLE (2475 1950);
FORCEPROP 1 LAST BODY_TYPE PLUMBING
J 0
(2475 2000);
DISPLAY 0.872340 (2475 2000);
PAINT GREEN (2475 2000);
DISPLAY INVISIBLE (2475 2000);
FORCEPROP 1 LAST HDL_TAP TRUE
J 0
(2800 1825);
DISPLAY 0.872340 (2800 1825);
DISPLAY INVISIBLE (2800 1825);
FORCEPROP 1 LAST PATH I119
J 0
(2473 1950);
DISPLAY 0.872340 (2473 1950);
PAINT GREEN (2473 1950);
DISPLAY INVISIBLE (2473 1950);
FORCEADD TAP..1
R 2
(-950 100);
FORCEPROP 3 LASTPIN (-900 100) SIG_NAME M_B_CPU1_SB_CB<3>
J 0
(-890 110);
DISPLAY 0.659574 (-890 110);
PAINT MONO (-890 110);
DISPLAY INVISIBLE (-890 110);
FORCEPROP 1 LASTPIN (-900 100) BN 3
J 2
(-888 108);
DISPLAY 0.680851 (-888 108);
PAINT GREEN (-888 108);
FORCEPROP 2 LAST CDS_LIB standard
J 0
(-950 100);
DISPLAY INVISIBLE (-950 100);
FORCEPROP 1 LAST BODY_TYPE PLUMBING
J 2
(-950 150);
DISPLAY 0.872340 (-950 150);
PAINT GREEN (-950 150);
DISPLAY INVISIBLE (-950 150);
FORCEPROP 1 LAST HDL_TAP TRUE
J 2
(-1275 -25);
DISPLAY 0.872340 (-1275 -25);
DISPLAY INVISIBLE (-1275 -25);
FORCEPROP 1 LAST PATH I12
J 2
(-948 100);
DISPLAY 0.872340 (-948 100);
PAINT GREEN (-948 100);
DISPLAY INVISIBLE (-948 100);
FORCEADD TAP..1
(2475 1900);
FORCEPROP 3 LASTPIN (2425 1900) SIG_NAME M_B_CPU1_SB_DQS_DN<3>
J 0
(2435 1910);
DISPLAY 0.659574 (2435 1910);
PAINT MONO (2435 1910);
DISPLAY INVISIBLE (2435 1910);
FORCEPROP 1 LASTPIN (2425 1900) BN 3
J 0
(2413 1908);
DISPLAY 0.680851 (2413 1908);
PAINT GREEN (2413 1908);
FORCEPROP 2 LAST CDS_LIB standard
J 0
(2475 1900);
DISPLAY INVISIBLE (2475 1900);
FORCEPROP 1 LAST BODY_TYPE PLUMBING
J 0
(2475 1950);
DISPLAY 0.872340 (2475 1950);
PAINT GREEN (2475 1950);
DISPLAY INVISIBLE (2475 1950);
FORCEPROP 1 LAST HDL_TAP TRUE
J 0
(2800 1775);
DISPLAY 0.872340 (2800 1775);
DISPLAY INVISIBLE (2800 1775);
FORCEPROP 1 LAST PATH I120
J 0
(2473 1900);
DISPLAY 0.872340 (2473 1900);
PAINT GREEN (2473 1900);
DISPLAY INVISIBLE (2473 1900);
FORCEADD TAP..1
(2475 1850);
FORCEPROP 3 LASTPIN (2425 1850) SIG_NAME M_B_CPU1_SB_DQS_DN<2>
J 0
(2435 1860);
DISPLAY 0.659574 (2435 1860);
PAINT MONO (2435 1860);
DISPLAY INVISIBLE (2435 1860);
FORCEPROP 1 LASTPIN (2425 1850) BN 2
J 0
(2413 1858);
DISPLAY 0.680851 (2413 1858);
PAINT GREEN (2413 1858);
FORCEPROP 2 LAST CDS_LIB standard
J 0
(2475 1850);
DISPLAY INVISIBLE (2475 1850);
FORCEPROP 1 LAST BODY_TYPE PLUMBING
J 0
(2475 1900);
DISPLAY 0.872340 (2475 1900);
PAINT GREEN (2475 1900);
DISPLAY INVISIBLE (2475 1900);
FORCEPROP 1 LAST HDL_TAP TRUE
J 0
(2800 1725);
DISPLAY 0.872340 (2800 1725);
DISPLAY INVISIBLE (2800 1725);
FORCEPROP 1 LAST PATH I121
J 0
(2473 1850);
DISPLAY 0.872340 (2473 1850);
PAINT GREEN (2473 1850);
DISPLAY INVISIBLE (2473 1850);
FORCEADD TAP..1
(2475 1750);
FORCEPROP 3 LASTPIN (2425 1750) SIG_NAME M_B_CPU1_SB_DQS_DN<0>
J 0
(2435 1760);
DISPLAY 0.659574 (2435 1760);
PAINT MONO (2435 1760);
DISPLAY INVISIBLE (2435 1760);
FORCEPROP 1 LASTPIN (2425 1750) BN 0
J 0
(2413 1758);
DISPLAY 0.680851 (2413 1758);
PAINT GREEN (2413 1758);
FORCEPROP 2 LAST CDS_LIB standard
J 0
(2475 1750);
DISPLAY INVISIBLE (2475 1750);
FORCEPROP 1 LAST BODY_TYPE PLUMBING
J 0
(2475 1800);
DISPLAY 0.872340 (2475 1800);
PAINT GREEN (2475 1800);
DISPLAY INVISIBLE (2475 1800);
FORCEPROP 1 LAST HDL_TAP TRUE
J 0
(2800 1625);
DISPLAY 0.872340 (2800 1625);
DISPLAY INVISIBLE (2800 1625);
FORCEPROP 1 LAST PATH I122
J 0
(2473 1750);
DISPLAY 0.872340 (2473 1750);
PAINT GREEN (2473 1750);
DISPLAY INVISIBLE (2473 1750);
FORCEADD TAP..1
(2475 2200);
FORCEPROP 3 LASTPIN (2425 2200) SIG_NAME M_B_CPU1_SB_DQS_DN<9>
J 0
(2435 2210);
DISPLAY 0.659574 (2435 2210);
PAINT MONO (2435 2210);
DISPLAY INVISIBLE (2435 2210);
FORCEPROP 1 LASTPIN (2425 2200) BN 9
J 0
(2413 2208);
DISPLAY 0.680851 (2413 2208);
PAINT GREEN (2413 2208);
FORCEPROP 2 LAST CDS_LIB standard
J 0
(2475 2200);
DISPLAY INVISIBLE (2475 2200);
FORCEPROP 1 LAST BODY_TYPE PLUMBING
J 0
(2475 2250);
DISPLAY 0.872340 (2475 2250);
PAINT GREEN (2475 2250);
DISPLAY INVISIBLE (2475 2250);
FORCEPROP 1 LAST HDL_TAP TRUE
J 0
(2800 2075);
DISPLAY 0.872340 (2800 2075);
DISPLAY INVISIBLE (2800 2075);
FORCEPROP 1 LAST PATH I123
J 0
(2473 2200);
DISPLAY 0.872340 (2473 2200);
PAINT GREEN (2473 2200);
DISPLAY INVISIBLE (2473 2200);
FORCEADD TAP..1
(2475 2150);
FORCEPROP 3 LASTPIN (2425 2150) SIG_NAME M_B_CPU1_SB_DQS_DN<8>
J 0
(2435 2160);
DISPLAY 0.659574 (2435 2160);
PAINT MONO (2435 2160);
DISPLAY INVISIBLE (2435 2160);
FORCEPROP 1 LASTPIN (2425 2150) BN 8
J 0
(2413 2158);
DISPLAY 0.680851 (2413 2158);
PAINT GREEN (2413 2158);
FORCEPROP 2 LAST CDS_LIB standard
J 0
(2475 2150);
DISPLAY INVISIBLE (2475 2150);
FORCEPROP 1 LAST BODY_TYPE PLUMBING
J 0
(2475 2200);
DISPLAY 0.872340 (2475 2200);
PAINT GREEN (2475 2200);
DISPLAY INVISIBLE (2475 2200);
FORCEPROP 1 LAST HDL_TAP TRUE
J 0
(2800 2025);
DISPLAY 0.872340 (2800 2025);
DISPLAY INVISIBLE (2800 2025);
FORCEPROP 1 LAST PATH I124
J 0
(2473 2150);
DISPLAY 0.872340 (2473 2150);
PAINT GREEN (2473 2150);
DISPLAY INVISIBLE (2473 2150);
FORCEADD TAP..1
(2475 2100);
FORCEPROP 3 LASTPIN (2425 2100) SIG_NAME M_B_CPU1_SB_DQS_DN<7>
J 0
(2435 2110);
DISPLAY 0.659574 (2435 2110);
PAINT MONO (2435 2110);
DISPLAY INVISIBLE (2435 2110);
FORCEPROP 1 LASTPIN (2425 2100) BN 7
J 0
(2413 2108);
DISPLAY 0.680851 (2413 2108);
PAINT GREEN (2413 2108);
FORCEPROP 2 LAST CDS_LIB standard
J 0
(2475 2100);
DISPLAY INVISIBLE (2475 2100);
FORCEPROP 1 LAST BODY_TYPE PLUMBING
J 0
(2475 2150);
DISPLAY 0.872340 (2475 2150);
PAINT GREEN (2475 2150);
DISPLAY INVISIBLE (2475 2150);
FORCEPROP 1 LAST HDL_TAP TRUE
J 0
(2800 1975);
DISPLAY 0.872340 (2800 1975);
DISPLAY INVISIBLE (2800 1975);
FORCEPROP 1 LAST PATH I125
J 0
(2473 2100);
DISPLAY 0.872340 (2473 2100);
PAINT GREEN (2473 2100);
DISPLAY INVISIBLE (2473 2100);
FORCEADD TAP..1
(2475 2050);
FORCEPROP 3 LASTPIN (2425 2050) SIG_NAME M_B_CPU1_SB_DQS_DN<6>
J 0
(2435 2060);
DISPLAY 0.659574 (2435 2060);
PAINT MONO (2435 2060);
DISPLAY INVISIBLE (2435 2060);
FORCEPROP 1 LASTPIN (2425 2050) BN 6
J 0
(2413 2058);
DISPLAY 0.680851 (2413 2058);
PAINT GREEN (2413 2058);
FORCEPROP 2 LAST CDS_LIB standard
J 0
(2475 2050);
DISPLAY INVISIBLE (2475 2050);
FORCEPROP 1 LAST BODY_TYPE PLUMBING
J 0
(2475 2100);
DISPLAY 0.872340 (2475 2100);
PAINT GREEN (2475 2100);
DISPLAY INVISIBLE (2475 2100);
FORCEPROP 1 LAST HDL_TAP TRUE
J 0
(2800 1925);
DISPLAY 0.872340 (2800 1925);
DISPLAY INVISIBLE (2800 1925);
FORCEPROP 1 LAST PATH I126
J 0
(2473 2050);
DISPLAY 0.872340 (2473 2050);
PAINT GREEN (2473 2050);
DISPLAY INVISIBLE (2473 2050);
FORCEADD TAP..1
(2475 2000);
FORCEPROP 3 LASTPIN (2425 2000) SIG_NAME M_B_CPU1_SB_DQS_DN<5>
J 0
(2435 2010);
DISPLAY 0.659574 (2435 2010);
PAINT MONO (2435 2010);
DISPLAY INVISIBLE (2435 2010);
FORCEPROP 1 LASTPIN (2425 2000) BN 5
J 0
(2413 2008);
DISPLAY 0.680851 (2413 2008);
PAINT GREEN (2413 2008);
FORCEPROP 2 LAST CDS_LIB standard
J 0
(2475 2000);
DISPLAY INVISIBLE (2475 2000);
FORCEPROP 1 LAST BODY_TYPE PLUMBING
J 0
(2475 2050);
DISPLAY 0.872340 (2475 2050);
PAINT GREEN (2475 2050);
DISPLAY INVISIBLE (2475 2050);
FORCEPROP 1 LAST HDL_TAP TRUE
J 0
(2800 1875);
DISPLAY 0.872340 (2800 1875);
DISPLAY INVISIBLE (2800 1875);
FORCEPROP 1 LAST PATH I127
J 0
(2473 2000);
DISPLAY 0.872340 (2473 2000);
PAINT GREEN (2473 2000);
DISPLAY INVISIBLE (2473 2000);
FORCEADD TAP..1
(2475 2350);
FORCEPROP 3 LASTPIN (2425 2350) SIG_NAME M_B_CPU1_SB_DQS_DP<1>
J 0
(2435 2360);
DISPLAY 0.659574 (2435 2360);
PAINT MONO (2435 2360);
DISPLAY INVISIBLE (2435 2360);
FORCEPROP 1 LASTPIN (2425 2350) BN 1
J 0
(2413 2358);
DISPLAY 0.680851 (2413 2358);
PAINT GREEN (2413 2358);
FORCEPROP 2 LAST CDS_LIB standard
J 0
(2475 2350);
DISPLAY INVISIBLE (2475 2350);
FORCEPROP 1 LAST BODY_TYPE PLUMBING
J 0
(2475 2400);
DISPLAY 0.872340 (2475 2400);
PAINT GREEN (2475 2400);
DISPLAY INVISIBLE (2475 2400);
FORCEPROP 1 LAST HDL_TAP TRUE
J 0
(2800 2225);
DISPLAY 0.872340 (2800 2225);
DISPLAY INVISIBLE (2800 2225);
FORCEPROP 1 LAST PATH I128
J 0
(2473 2350);
DISPLAY 0.872340 (2473 2350);
PAINT GREEN (2473 2350);
DISPLAY INVISIBLE (2473 2350);
FORCEADD TAP..1
(2475 2400);
FORCEPROP 3 LASTPIN (2425 2400) SIG_NAME M_B_CPU1_SB_DQS_DP<2>
J 0
(2435 2410);
DISPLAY 0.659574 (2435 2410);
PAINT MONO (2435 2410);
DISPLAY INVISIBLE (2435 2410);
FORCEPROP 1 LASTPIN (2425 2400) BN 2
J 0
(2413 2408);
DISPLAY 0.680851 (2413 2408);
PAINT GREEN (2413 2408);
FORCEPROP 2 LAST CDS_LIB standard
J 0
(2475 2400);
DISPLAY INVISIBLE (2475 2400);
FORCEPROP 1 LAST BODY_TYPE PLUMBING
J 0
(2475 2450);
DISPLAY 0.872340 (2475 2450);
PAINT GREEN (2475 2450);
DISPLAY INVISIBLE (2475 2450);
FORCEPROP 1 LAST HDL_TAP TRUE
J 0
(2800 2275);
DISPLAY 0.872340 (2800 2275);
DISPLAY INVISIBLE (2800 2275);
FORCEPROP 1 LAST PATH I129
J 0
(2473 2400);
DISPLAY 0.872340 (2473 2400);
PAINT GREEN (2473 2400);
DISPLAY INVISIBLE (2473 2400);
FORCEADD TAP..1
R 2
(-950 150);
FORCEPROP 3 LASTPIN (-900 150) SIG_NAME M_B_CPU1_SB_CB<4>
J 0
(-890 160);
DISPLAY 0.659574 (-890 160);
PAINT MONO (-890 160);
DISPLAY INVISIBLE (-890 160);
FORCEPROP 1 LASTPIN (-900 150) BN 4
J 2
(-888 158);
DISPLAY 0.680851 (-888 158);
PAINT GREEN (-888 158);
FORCEPROP 2 LAST CDS_LIB standard
J 0
(-950 150);
DISPLAY INVISIBLE (-950 150);
FORCEPROP 1 LAST BODY_TYPE PLUMBING
J 2
(-950 200);
DISPLAY 0.872340 (-950 200);
PAINT GREEN (-950 200);
DISPLAY INVISIBLE (-950 200);
FORCEPROP 1 LAST HDL_TAP TRUE
J 2
(-1275 25);
DISPLAY 0.872340 (-1275 25);
DISPLAY INVISIBLE (-1275 25);
FORCEPROP 1 LAST PATH I13
J 2
(-948 150);
DISPLAY 0.872340 (-948 150);
PAINT GREEN (-948 150);
DISPLAY INVISIBLE (-948 150);
FORCEADD TAP..1
(2475 2450);
FORCEPROP 3 LASTPIN (2425 2450) SIG_NAME M_B_CPU1_SB_DQS_DP<3>
J 0
(2435 2460);
DISPLAY 0.659574 (2435 2460);
PAINT MONO (2435 2460);
DISPLAY INVISIBLE (2435 2460);
FORCEPROP 1 LASTPIN (2425 2450) BN 3
J 0
(2413 2458);
DISPLAY 0.680851 (2413 2458);
PAINT GREEN (2413 2458);
FORCEPROP 2 LAST CDS_LIB standard
J 0
(2475 2450);
DISPLAY INVISIBLE (2475 2450);
FORCEPROP 1 LAST BODY_TYPE PLUMBING
J 0
(2475 2500);
DISPLAY 0.872340 (2475 2500);
PAINT GREEN (2475 2500);
DISPLAY INVISIBLE (2475 2500);
FORCEPROP 1 LAST HDL_TAP TRUE
J 0
(2800 2325);
DISPLAY 0.872340 (2800 2325);
DISPLAY INVISIBLE (2800 2325);
FORCEPROP 1 LAST PATH I130
J 0
(2473 2450);
DISPLAY 0.872340 (2473 2450);
PAINT GREEN (2473 2450);
DISPLAY INVISIBLE (2473 2450);
FORCEADD TAP..1
(2475 2300);
FORCEPROP 3 LASTPIN (2425 2300) SIG_NAME M_B_CPU1_SB_DQS_DP<0>
J 0
(2435 2310);
DISPLAY 0.659574 (2435 2310);
PAINT MONO (2435 2310);
DISPLAY INVISIBLE (2435 2310);
FORCEPROP 1 LASTPIN (2425 2300) BN 0
J 0
(2413 2308);
DISPLAY 0.680851 (2413 2308);
PAINT GREEN (2413 2308);
FORCEPROP 2 LAST CDS_LIB standard
J 0
(2475 2300);
DISPLAY INVISIBLE (2475 2300);
FORCEPROP 1 LAST BODY_TYPE PLUMBING
J 0
(2475 2350);
DISPLAY 0.872340 (2475 2350);
PAINT GREEN (2475 2350);
DISPLAY INVISIBLE (2475 2350);
FORCEPROP 1 LAST HDL_TAP TRUE
J 0
(2800 2175);
DISPLAY 0.872340 (2800 2175);
DISPLAY INVISIBLE (2800 2175);
FORCEPROP 1 LAST PATH I131
J 0
(2473 2300);
DISPLAY 0.872340 (2473 2300);
PAINT GREEN (2473 2300);
DISPLAY INVISIBLE (2473 2300);
FORCEADD TAP..1
(2475 2550);
FORCEPROP 3 LASTPIN (2425 2550) SIG_NAME M_B_CPU1_SB_DQS_DP<5>
J 0
(2435 2560);
DISPLAY 0.659574 (2435 2560);
PAINT MONO (2435 2560);
DISPLAY INVISIBLE (2435 2560);
FORCEPROP 1 LASTPIN (2425 2550) BN 5
J 0
(2413 2558);
DISPLAY 0.680851 (2413 2558);
PAINT GREEN (2413 2558);
FORCEPROP 2 LAST CDS_LIB standard
J 0
(2475 2550);
DISPLAY INVISIBLE (2475 2550);
FORCEPROP 1 LAST BODY_TYPE PLUMBING
J 0
(2475 2600);
DISPLAY 0.872340 (2475 2600);
PAINT GREEN (2475 2600);
DISPLAY INVISIBLE (2475 2600);
FORCEPROP 1 LAST HDL_TAP TRUE
J 0
(2800 2425);
DISPLAY 0.872340 (2800 2425);
DISPLAY INVISIBLE (2800 2425);
FORCEPROP 1 LAST PATH I132
J 0
(2473 2550);
DISPLAY 0.872340 (2473 2550);
PAINT GREEN (2473 2550);
DISPLAY INVISIBLE (2473 2550);
FORCEADD TAP..1
(2475 2700);
FORCEPROP 3 LASTPIN (2425 2700) SIG_NAME M_B_CPU1_SB_DQS_DP<8>
J 0
(2435 2710);
DISPLAY 0.659574 (2435 2710);
PAINT MONO (2435 2710);
DISPLAY INVISIBLE (2435 2710);
FORCEPROP 1 LASTPIN (2425 2700) BN 8
J 0
(2413 2708);
DISPLAY 0.680851 (2413 2708);
PAINT GREEN (2413 2708);
FORCEPROP 2 LAST CDS_LIB standard
J 0
(2475 2700);
DISPLAY INVISIBLE (2475 2700);
FORCEPROP 1 LAST BODY_TYPE PLUMBING
J 0
(2475 2750);
DISPLAY 0.872340 (2475 2750);
PAINT GREEN (2475 2750);
DISPLAY INVISIBLE (2475 2750);
FORCEPROP 1 LAST HDL_TAP TRUE
J 0
(2800 2575);
DISPLAY 0.872340 (2800 2575);
DISPLAY INVISIBLE (2800 2575);
FORCEPROP 1 LAST PATH I133
J 0
(2473 2700);
DISPLAY 0.872340 (2473 2700);
PAINT GREEN (2473 2700);
DISPLAY INVISIBLE (2473 2700);
FORCEADD TAP..1
(2475 2650);
FORCEPROP 3 LASTPIN (2425 2650) SIG_NAME M_B_CPU1_SB_DQS_DP<7>
J 0
(2435 2660);
DISPLAY 0.659574 (2435 2660);
PAINT MONO (2435 2660);
DISPLAY INVISIBLE (2435 2660);
FORCEPROP 1 LASTPIN (2425 2650) BN 7
J 0
(2413 2658);
DISPLAY 0.680851 (2413 2658);
PAINT GREEN (2413 2658);
FORCEPROP 2 LAST CDS_LIB standard
J 0
(2475 2650);
DISPLAY INVISIBLE (2475 2650);
FORCEPROP 1 LAST BODY_TYPE PLUMBING
J 0
(2475 2700);
DISPLAY 0.872340 (2475 2700);
PAINT GREEN (2475 2700);
DISPLAY INVISIBLE (2475 2700);
FORCEPROP 1 LAST HDL_TAP TRUE
J 0
(2800 2525);
DISPLAY 0.872340 (2800 2525);
DISPLAY INVISIBLE (2800 2525);
FORCEPROP 1 LAST PATH I134
J 0
(2473 2650);
DISPLAY 0.872340 (2473 2650);
PAINT GREEN (2473 2650);
DISPLAY INVISIBLE (2473 2650);
FORCEADD TAP..1
(2475 2600);
FORCEPROP 3 LASTPIN (2425 2600) SIG_NAME M_B_CPU1_SB_DQS_DP<6>
J 0
(2435 2610);
DISPLAY 0.659574 (2435 2610);
PAINT MONO (2435 2610);
DISPLAY INVISIBLE (2435 2610);
FORCEPROP 1 LASTPIN (2425 2600) BN 6
J 0
(2413 2608);
DISPLAY 0.680851 (2413 2608);
PAINT GREEN (2413 2608);
FORCEPROP 2 LAST CDS_LIB standard
J 0
(2475 2600);
DISPLAY INVISIBLE (2475 2600);
FORCEPROP 1 LAST BODY_TYPE PLUMBING
J 0
(2475 2650);
DISPLAY 0.872340 (2475 2650);
PAINT GREEN (2475 2650);
DISPLAY INVISIBLE (2475 2650);
FORCEPROP 1 LAST HDL_TAP TRUE
J 0
(2800 2475);
DISPLAY 0.872340 (2800 2475);
DISPLAY INVISIBLE (2800 2475);
FORCEPROP 1 LAST PATH I135
J 0
(2473 2600);
DISPLAY 0.872340 (2473 2600);
PAINT GREEN (2473 2600);
DISPLAY INVISIBLE (2473 2600);
FORCEADD TAP..1
(2475 2500);
FORCEPROP 3 LASTPIN (2425 2500) SIG_NAME M_B_CPU1_SB_DQS_DP<4>
J 0
(2435 2510);
DISPLAY 0.659574 (2435 2510);
PAINT MONO (2435 2510);
DISPLAY INVISIBLE (2435 2510);
FORCEPROP 1 LASTPIN (2425 2500) BN 4
J 0
(2413 2508);
DISPLAY 0.680851 (2413 2508);
PAINT GREEN (2413 2508);
FORCEPROP 2 LAST CDS_LIB standard
J 0
(2475 2500);
DISPLAY INVISIBLE (2475 2500);
FORCEPROP 1 LAST BODY_TYPE PLUMBING
J 0
(2475 2550);
DISPLAY 0.872340 (2475 2550);
PAINT GREEN (2475 2550);
DISPLAY INVISIBLE (2475 2550);
FORCEPROP 1 LAST HDL_TAP TRUE
J 0
(2800 2375);
DISPLAY 0.872340 (2800 2375);
DISPLAY INVISIBLE (2800 2375);
FORCEPROP 1 LAST PATH I136
J 0
(2473 2500);
DISPLAY 0.872340 (2473 2500);
PAINT GREEN (2473 2500);
DISPLAY INVISIBLE (2473 2500);
FORCEADD TAP..1
(2475 2750);
FORCEPROP 3 LASTPIN (2425 2750) SIG_NAME M_B_CPU1_SB_DQS_DP<9>
J 0
(2435 2760);
DISPLAY 0.659574 (2435 2760);
PAINT MONO (2435 2760);
DISPLAY INVISIBLE (2435 2760);
FORCEPROP 1 LASTPIN (2425 2750) BN 9
J 0
(2413 2758);
DISPLAY 0.680851 (2413 2758);
PAINT GREEN (2413 2758);
FORCEPROP 2 LAST CDS_LIB standard
J 0
(2475 2750);
DISPLAY INVISIBLE (2475 2750);
FORCEPROP 1 LAST BODY_TYPE PLUMBING
J 0
(2475 2800);
DISPLAY 0.872340 (2475 2800);
PAINT GREEN (2475 2800);
DISPLAY INVISIBLE (2475 2800);
FORCEPROP 1 LAST HDL_TAP TRUE
J 0
(2800 2625);
DISPLAY 0.872340 (2800 2625);
DISPLAY INVISIBLE (2800 2625);
FORCEPROP 1 LAST PATH I137
J 0
(2473 2750);
DISPLAY 0.872340 (2473 2750);
PAINT GREEN (2473 2750);
DISPLAY INVISIBLE (2473 2750);
FORCEADD TAP..1
(2475 2900);
FORCEPROP 3 LASTPIN (2425 2900) SIG_NAME M_B_CPU1_SA_DQS_DN<0>
J 0
(2435 2910);
DISPLAY 0.659574 (2435 2910);
PAINT MONO (2435 2910);
DISPLAY INVISIBLE (2435 2910);
FORCEPROP 1 LASTPIN (2425 2900) BN 0
J 0
(2413 2908);
DISPLAY 0.680851 (2413 2908);
PAINT GREEN (2413 2908);
FORCEPROP 2 LAST CDS_LIB standard
J 0
(2475 2900);
DISPLAY INVISIBLE (2475 2900);
FORCEPROP 1 LAST BODY_TYPE PLUMBING
J 0
(2475 2950);
DISPLAY 0.872340 (2475 2950);
PAINT GREEN (2475 2950);
DISPLAY INVISIBLE (2475 2950);
FORCEPROP 1 LAST HDL_TAP TRUE
J 0
(2800 2775);
DISPLAY 0.872340 (2800 2775);
DISPLAY INVISIBLE (2800 2775);
FORCEPROP 1 LAST PATH I138
J 0
(2473 2900);
DISPLAY 0.872340 (2473 2900);
PAINT GREEN (2473 2900);
DISPLAY INVISIBLE (2473 2900);
FORCEADD TAP..1
(2475 2950);
FORCEPROP 3 LASTPIN (2425 2950) SIG_NAME M_B_CPU1_SA_DQS_DN<1>
J 0
(2435 2960);
DISPLAY 0.659574 (2435 2960);
PAINT MONO (2435 2960);
DISPLAY INVISIBLE (2435 2960);
FORCEPROP 1 LASTPIN (2425 2950) BN 1
J 0
(2413 2958);
DISPLAY 0.680851 (2413 2958);
PAINT GREEN (2413 2958);
FORCEPROP 2 LAST CDS_LIB standard
J 0
(2475 2950);
DISPLAY INVISIBLE (2475 2950);
FORCEPROP 1 LAST BODY_TYPE PLUMBING
J 0
(2475 3000);
DISPLAY 0.872340 (2475 3000);
PAINT GREEN (2475 3000);
DISPLAY INVISIBLE (2475 3000);
FORCEPROP 1 LAST HDL_TAP TRUE
J 0
(2800 2825);
DISPLAY 0.872340 (2800 2825);
DISPLAY INVISIBLE (2800 2825);
FORCEPROP 1 LAST PATH I139
J 0
(2473 2950);
DISPLAY 0.872340 (2473 2950);
PAINT GREEN (2473 2950);
DISPLAY INVISIBLE (2473 2950);
FORCEADD TAP..1
R 2
(-950 200);
FORCEPROP 3 LASTPIN (-900 200) SIG_NAME M_B_CPU1_SB_CB<5>
J 0
(-890 210);
DISPLAY 0.659574 (-890 210);
PAINT MONO (-890 210);
DISPLAY INVISIBLE (-890 210);
FORCEPROP 1 LASTPIN (-900 200) BN 5
J 2
(-888 208);
DISPLAY 0.680851 (-888 208);
PAINT GREEN (-888 208);
FORCEPROP 2 LAST CDS_LIB standard
J 0
(-950 200);
DISPLAY INVISIBLE (-950 200);
FORCEPROP 1 LAST BODY_TYPE PLUMBING
J 2
(-950 250);
DISPLAY 0.872340 (-950 250);
PAINT GREEN (-950 250);
DISPLAY INVISIBLE (-950 250);
FORCEPROP 1 LAST HDL_TAP TRUE
J 2
(-1275 75);
DISPLAY 0.872340 (-1275 75);
DISPLAY INVISIBLE (-1275 75);
FORCEPROP 1 LAST PATH I14
J 2
(-948 200);
DISPLAY 0.872340 (-948 200);
PAINT GREEN (-948 200);
DISPLAY INVISIBLE (-948 200);
FORCEADD TAP..1
(2475 3050);
FORCEPROP 3 LASTPIN (2425 3050) SIG_NAME M_B_CPU1_SA_DQS_DN<3>
J 0
(2435 3060);
DISPLAY 0.659574 (2435 3060);
PAINT MONO (2435 3060);
DISPLAY INVISIBLE (2435 3060);
FORCEPROP 1 LASTPIN (2425 3050) BN 3
J 0
(2413 3058);
DISPLAY 0.680851 (2413 3058);
PAINT GREEN (2413 3058);
FORCEPROP 2 LAST CDS_LIB standard
J 0
(2475 3050);
DISPLAY INVISIBLE (2475 3050);
FORCEPROP 1 LAST BODY_TYPE PLUMBING
J 0
(2475 3100);
DISPLAY 0.872340 (2475 3100);
PAINT GREEN (2475 3100);
DISPLAY INVISIBLE (2475 3100);
FORCEPROP 1 LAST HDL_TAP TRUE
J 0
(2800 2925);
DISPLAY 0.872340 (2800 2925);
DISPLAY INVISIBLE (2800 2925);
FORCEPROP 1 LAST PATH I140
J 0
(2473 3050);
DISPLAY 0.872340 (2473 3050);
PAINT GREEN (2473 3050);
DISPLAY INVISIBLE (2473 3050);
FORCEADD TAP..1
(2475 3200);
FORCEPROP 3 LASTPIN (2425 3200) SIG_NAME M_B_CPU1_SA_DQS_DN<6>
J 0
(2435 3210);
DISPLAY 0.659574 (2435 3210);
PAINT MONO (2435 3210);
DISPLAY INVISIBLE (2435 3210);
FORCEPROP 1 LASTPIN (2425 3200) BN 6
J 0
(2413 3208);
DISPLAY 0.680851 (2413 3208);
PAINT GREEN (2413 3208);
FORCEPROP 2 LAST CDS_LIB standard
J 0
(2475 3200);
DISPLAY INVISIBLE (2475 3200);
FORCEPROP 1 LAST BODY_TYPE PLUMBING
J 0
(2475 3250);
DISPLAY 0.872340 (2475 3250);
PAINT GREEN (2475 3250);
DISPLAY INVISIBLE (2475 3250);
FORCEPROP 1 LAST HDL_TAP TRUE
J 0
(2800 3075);
DISPLAY 0.872340 (2800 3075);
DISPLAY INVISIBLE (2800 3075);
FORCEPROP 1 LAST PATH I141
J 0
(2473 3200);
DISPLAY 0.872340 (2473 3200);
PAINT GREEN (2473 3200);
DISPLAY INVISIBLE (2473 3200);
FORCEADD TAP..1
(2475 3250);
FORCEPROP 3 LASTPIN (2425 3250) SIG_NAME M_B_CPU1_SA_DQS_DN<7>
J 0
(2435 3260);
DISPLAY 0.659574 (2435 3260);
PAINT MONO (2435 3260);
DISPLAY INVISIBLE (2435 3260);
FORCEPROP 1 LASTPIN (2425 3250) BN 7
J 0
(2413 3258);
DISPLAY 0.680851 (2413 3258);
PAINT GREEN (2413 3258);
FORCEPROP 2 LAST CDS_LIB standard
J 0
(2475 3250);
DISPLAY INVISIBLE (2475 3250);
FORCEPROP 1 LAST BODY_TYPE PLUMBING
J 0
(2475 3300);
DISPLAY 0.872340 (2475 3300);
PAINT GREEN (2475 3300);
DISPLAY INVISIBLE (2475 3300);
FORCEPROP 1 LAST HDL_TAP TRUE
J 0
(2800 3125);
DISPLAY 0.872340 (2800 3125);
DISPLAY INVISIBLE (2800 3125);
FORCEPROP 1 LAST PATH I142
J 0
(2473 3250);
DISPLAY 0.872340 (2473 3250);
PAINT GREEN (2473 3250);
DISPLAY INVISIBLE (2473 3250);
FORCEADD TAP..1
(2475 3150);
FORCEPROP 3 LASTPIN (2425 3150) SIG_NAME M_B_CPU1_SA_DQS_DN<5>
J 0
(2435 3160);
DISPLAY 0.659574 (2435 3160);
PAINT MONO (2435 3160);
DISPLAY INVISIBLE (2435 3160);
FORCEPROP 1 LASTPIN (2425 3150) BN 5
J 0
(2413 3158);
DISPLAY 0.680851 (2413 3158);
PAINT GREEN (2413 3158);
FORCEPROP 2 LAST CDS_LIB standard
J 0
(2475 3150);
DISPLAY INVISIBLE (2475 3150);
FORCEPROP 1 LAST BODY_TYPE PLUMBING
J 0
(2475 3200);
DISPLAY 0.872340 (2475 3200);
PAINT GREEN (2475 3200);
DISPLAY INVISIBLE (2475 3200);
FORCEPROP 1 LAST HDL_TAP TRUE
J 0
(2800 3025);
DISPLAY 0.872340 (2800 3025);
DISPLAY INVISIBLE (2800 3025);
FORCEPROP 1 LAST PATH I143
J 0
(2473 3150);
DISPLAY 0.872340 (2473 3150);
PAINT GREEN (2473 3150);
DISPLAY INVISIBLE (2473 3150);
FORCEADD TAP..1
(2475 3100);
FORCEPROP 3 LASTPIN (2425 3100) SIG_NAME M_B_CPU1_SA_DQS_DN<4>
J 0
(2435 3110);
DISPLAY 0.659574 (2435 3110);
PAINT MONO (2435 3110);
DISPLAY INVISIBLE (2435 3110);
FORCEPROP 1 LASTPIN (2425 3100) BN 4
J 0
(2413 3108);
DISPLAY 0.680851 (2413 3108);
PAINT GREEN (2413 3108);
FORCEPROP 2 LAST CDS_LIB standard
J 0
(2475 3100);
DISPLAY INVISIBLE (2475 3100);
FORCEPROP 1 LAST BODY_TYPE PLUMBING
J 0
(2475 3150);
DISPLAY 0.872340 (2475 3150);
PAINT GREEN (2475 3150);
DISPLAY INVISIBLE (2475 3150);
FORCEPROP 1 LAST HDL_TAP TRUE
J 0
(2800 2975);
DISPLAY 0.872340 (2800 2975);
DISPLAY INVISIBLE (2800 2975);
FORCEPROP 1 LAST PATH I144
J 0
(2473 3100);
DISPLAY 0.872340 (2473 3100);
PAINT GREEN (2473 3100);
DISPLAY INVISIBLE (2473 3100);
FORCEADD TAP..1
(2475 3000);
FORCEPROP 3 LASTPIN (2425 3000) SIG_NAME M_B_CPU1_SA_DQS_DN<2>
J 0
(2435 3010);
DISPLAY 0.659574 (2435 3010);
PAINT MONO (2435 3010);
DISPLAY INVISIBLE (2435 3010);
FORCEPROP 1 LASTPIN (2425 3000) BN 2
J 0
(2413 3008);
DISPLAY 0.680851 (2413 3008);
PAINT GREEN (2413 3008);
FORCEPROP 2 LAST CDS_LIB standard
J 0
(2475 3000);
DISPLAY INVISIBLE (2475 3000);
FORCEPROP 1 LAST BODY_TYPE PLUMBING
J 0
(2475 3050);
DISPLAY 0.872340 (2475 3050);
PAINT GREEN (2475 3050);
DISPLAY INVISIBLE (2475 3050);
FORCEPROP 1 LAST HDL_TAP TRUE
J 0
(2800 2875);
DISPLAY 0.872340 (2800 2875);
DISPLAY INVISIBLE (2800 2875);
FORCEPROP 1 LAST PATH I145
J 0
(2473 3000);
DISPLAY 0.872340 (2473 3000);
PAINT GREEN (2473 3000);
DISPLAY INVISIBLE (2473 3000);
FORCEADD TAP..1
(2475 3300);
FORCEPROP 3 LASTPIN (2425 3300) SIG_NAME M_B_CPU1_SA_DQS_DN<8>
J 0
(2435 3310);
DISPLAY 0.659574 (2435 3310);
PAINT MONO (2435 3310);
DISPLAY INVISIBLE (2435 3310);
FORCEPROP 1 LASTPIN (2425 3300) BN 8
J 0
(2413 3308);
DISPLAY 0.680851 (2413 3308);
PAINT GREEN (2413 3308);
FORCEPROP 2 LAST CDS_LIB standard
J 0
(2475 3300);
DISPLAY INVISIBLE (2475 3300);
FORCEPROP 1 LAST BODY_TYPE PLUMBING
J 0
(2475 3350);
DISPLAY 0.872340 (2475 3350);
PAINT GREEN (2475 3350);
DISPLAY INVISIBLE (2475 3350);
FORCEPROP 1 LAST HDL_TAP TRUE
J 0
(2800 3175);
DISPLAY 0.872340 (2800 3175);
DISPLAY INVISIBLE (2800 3175);
FORCEPROP 1 LAST PATH I146
J 0
(2473 3300);
DISPLAY 0.872340 (2473 3300);
PAINT GREEN (2473 3300);
DISPLAY INVISIBLE (2473 3300);
FORCEADD TAP..1
(2475 3500);
FORCEPROP 3 LASTPIN (2425 3500) SIG_NAME M_B_CPU1_SA_DQS_DP<1>
J 0
(2435 3510);
DISPLAY 0.659574 (2435 3510);
PAINT MONO (2435 3510);
DISPLAY INVISIBLE (2435 3510);
FORCEPROP 1 LASTPIN (2425 3500) BN 1
J 0
(2413 3508);
DISPLAY 0.680851 (2413 3508);
PAINT GREEN (2413 3508);
FORCEPROP 2 LAST CDS_LIB standard
J 0
(2475 3500);
DISPLAY INVISIBLE (2475 3500);
FORCEPROP 1 LAST BODY_TYPE PLUMBING
J 0
(2475 3550);
DISPLAY 0.872340 (2475 3550);
PAINT GREEN (2475 3550);
DISPLAY INVISIBLE (2475 3550);
FORCEPROP 1 LAST HDL_TAP TRUE
J 0
(2800 3375);
DISPLAY 0.872340 (2800 3375);
DISPLAY INVISIBLE (2800 3375);
FORCEPROP 1 LAST PATH I147
J 0
(2473 3500);
DISPLAY 0.872340 (2473 3500);
PAINT GREEN (2473 3500);
DISPLAY INVISIBLE (2473 3500);
FORCEADD TAP..1
(2475 3450);
FORCEPROP 3 LASTPIN (2425 3450) SIG_NAME M_B_CPU1_SA_DQS_DP<0>
J 0
(2435 3460);
DISPLAY 0.659574 (2435 3460);
PAINT MONO (2435 3460);
DISPLAY INVISIBLE (2435 3460);
FORCEPROP 1 LASTPIN (2425 3450) BN 0
J 0
(2413 3458);
DISPLAY 0.680851 (2413 3458);
PAINT GREEN (2413 3458);
FORCEPROP 2 LAST CDS_LIB standard
J 0
(2475 3450);
DISPLAY INVISIBLE (2475 3450);
FORCEPROP 1 LAST BODY_TYPE PLUMBING
J 0
(2475 3500);
DISPLAY 0.872340 (2475 3500);
PAINT GREEN (2475 3500);
DISPLAY INVISIBLE (2475 3500);
FORCEPROP 1 LAST HDL_TAP TRUE
J 0
(2800 3325);
DISPLAY 0.872340 (2800 3325);
DISPLAY INVISIBLE (2800 3325);
FORCEPROP 1 LAST PATH I148
J 0
(2473 3450);
DISPLAY 0.872340 (2473 3450);
PAINT GREEN (2473 3450);
DISPLAY INVISIBLE (2473 3450);
FORCEADD TAP..1
(2475 3350);
FORCEPROP 3 LASTPIN (2425 3350) SIG_NAME M_B_CPU1_SA_DQS_DN<9>
J 0
(2435 3360);
DISPLAY 0.659574 (2435 3360);
PAINT MONO (2435 3360);
DISPLAY INVISIBLE (2435 3360);
FORCEPROP 1 LASTPIN (2425 3350) BN 9
J 0
(2413 3358);
DISPLAY 0.680851 (2413 3358);
PAINT GREEN (2413 3358);
FORCEPROP 2 LAST CDS_LIB standard
J 0
(2475 3350);
DISPLAY INVISIBLE (2475 3350);
FORCEPROP 1 LAST BODY_TYPE PLUMBING
J 0
(2475 3400);
DISPLAY 0.872340 (2475 3400);
PAINT GREEN (2475 3400);
DISPLAY INVISIBLE (2475 3400);
FORCEPROP 1 LAST HDL_TAP TRUE
J 0
(2800 3225);
DISPLAY 0.872340 (2800 3225);
DISPLAY INVISIBLE (2800 3225);
FORCEPROP 1 LAST PATH I149
J 0
(2473 3350);
DISPLAY 0.872340 (2473 3350);
PAINT GREEN (2473 3350);
DISPLAY INVISIBLE (2473 3350);
FORCEADD TAP..1
R 2
(-950 250);
FORCEPROP 3 LASTPIN (-900 250) SIG_NAME M_B_CPU1_SB_CB<6>
J 0
(-890 260);
DISPLAY 0.659574 (-890 260);
PAINT MONO (-890 260);
DISPLAY INVISIBLE (-890 260);
FORCEPROP 1 LASTPIN (-900 250) BN 6
J 2
(-888 258);
DISPLAY 0.680851 (-888 258);
PAINT GREEN (-888 258);
FORCEPROP 2 LAST CDS_LIB standard
J 0
(-950 250);
DISPLAY INVISIBLE (-950 250);
FORCEPROP 1 LAST BODY_TYPE PLUMBING
J 2
(-950 300);
DISPLAY 0.872340 (-950 300);
PAINT GREEN (-950 300);
DISPLAY INVISIBLE (-950 300);
FORCEPROP 1 LAST HDL_TAP TRUE
J 2
(-1275 125);
DISPLAY 0.872340 (-1275 125);
DISPLAY INVISIBLE (-1275 125);
FORCEPROP 1 LAST PATH I15
J 2
(-948 250);
DISPLAY 0.872340 (-948 250);
PAINT GREEN (-948 250);
DISPLAY INVISIBLE (-948 250);
FORCEADD TAP..1
(2475 3600);
FORCEPROP 3 LASTPIN (2425 3600) SIG_NAME M_B_CPU1_SA_DQS_DP<3>
J 0
(2435 3610);
DISPLAY 0.659574 (2435 3610);
PAINT MONO (2435 3610);
DISPLAY INVISIBLE (2435 3610);
FORCEPROP 1 LASTPIN (2425 3600) BN 3
J 0
(2413 3608);
DISPLAY 0.680851 (2413 3608);
PAINT GREEN (2413 3608);
FORCEPROP 2 LAST CDS_LIB standard
J 0
(2475 3600);
DISPLAY INVISIBLE (2475 3600);
FORCEPROP 1 LAST BODY_TYPE PLUMBING
J 0
(2475 3650);
DISPLAY 0.872340 (2475 3650);
PAINT GREEN (2475 3650);
DISPLAY INVISIBLE (2475 3650);
FORCEPROP 1 LAST HDL_TAP TRUE
J 0
(2800 3475);
DISPLAY 0.872340 (2800 3475);
DISPLAY INVISIBLE (2800 3475);
FORCEPROP 1 LAST PATH I150
J 0
(2473 3600);
DISPLAY 0.872340 (2473 3600);
PAINT GREEN (2473 3600);
DISPLAY INVISIBLE (2473 3600);
FORCEADD TAP..1
(2475 3750);
FORCEPROP 3 LASTPIN (2425 3750) SIG_NAME M_B_CPU1_SA_DQS_DP<6>
J 0
(2435 3760);
DISPLAY 0.659574 (2435 3760);
PAINT MONO (2435 3760);
DISPLAY INVISIBLE (2435 3760);
FORCEPROP 1 LASTPIN (2425 3750) BN 6
J 0
(2413 3758);
DISPLAY 0.680851 (2413 3758);
PAINT GREEN (2413 3758);
FORCEPROP 2 LAST CDS_LIB standard
J 0
(2475 3750);
DISPLAY INVISIBLE (2475 3750);
FORCEPROP 1 LAST BODY_TYPE PLUMBING
J 0
(2475 3800);
DISPLAY 0.872340 (2475 3800);
PAINT GREEN (2475 3800);
DISPLAY INVISIBLE (2475 3800);
FORCEPROP 1 LAST HDL_TAP TRUE
J 0
(2800 3625);
DISPLAY 0.872340 (2800 3625);
DISPLAY INVISIBLE (2800 3625);
FORCEPROP 1 LAST PATH I151
J 0
(2473 3750);
DISPLAY 0.872340 (2473 3750);
PAINT GREEN (2473 3750);
DISPLAY INVISIBLE (2473 3750);
FORCEADD TAP..1
(2475 3700);
FORCEPROP 3 LASTPIN (2425 3700) SIG_NAME M_B_CPU1_SA_DQS_DP<5>
J 0
(2435 3710);
DISPLAY 0.659574 (2435 3710);
PAINT MONO (2435 3710);
DISPLAY INVISIBLE (2435 3710);
FORCEPROP 1 LASTPIN (2425 3700) BN 5
J 0
(2413 3708);
DISPLAY 0.680851 (2413 3708);
PAINT GREEN (2413 3708);
FORCEPROP 2 LAST CDS_LIB standard
J 0
(2475 3700);
DISPLAY INVISIBLE (2475 3700);
FORCEPROP 1 LAST BODY_TYPE PLUMBING
J 0
(2475 3750);
DISPLAY 0.872340 (2475 3750);
PAINT GREEN (2475 3750);
DISPLAY INVISIBLE (2475 3750);
FORCEPROP 1 LAST HDL_TAP TRUE
J 0
(2800 3575);
DISPLAY 0.872340 (2800 3575);
DISPLAY INVISIBLE (2800 3575);
FORCEPROP 1 LAST PATH I152
J 0
(2473 3700);
DISPLAY 0.872340 (2473 3700);
PAINT GREEN (2473 3700);
DISPLAY INVISIBLE (2473 3700);
FORCEADD TAP..1
(2475 3550);
FORCEPROP 3 LASTPIN (2425 3550) SIG_NAME M_B_CPU1_SA_DQS_DP<2>
J 0
(2435 3560);
DISPLAY 0.659574 (2435 3560);
PAINT MONO (2435 3560);
DISPLAY INVISIBLE (2435 3560);
FORCEPROP 1 LASTPIN (2425 3550) BN 2
J 0
(2413 3558);
DISPLAY 0.680851 (2413 3558);
PAINT GREEN (2413 3558);
FORCEPROP 2 LAST CDS_LIB standard
J 0
(2475 3550);
DISPLAY INVISIBLE (2475 3550);
FORCEPROP 1 LAST BODY_TYPE PLUMBING
J 0
(2475 3600);
DISPLAY 0.872340 (2475 3600);
PAINT GREEN (2475 3600);
DISPLAY INVISIBLE (2475 3600);
FORCEPROP 1 LAST HDL_TAP TRUE
J 0
(2800 3425);
DISPLAY 0.872340 (2800 3425);
DISPLAY INVISIBLE (2800 3425);
FORCEPROP 1 LAST PATH I153
J 0
(2473 3550);
DISPLAY 0.872340 (2473 3550);
PAINT GREEN (2473 3550);
DISPLAY INVISIBLE (2473 3550);
FORCEADD TAP..1
(2475 3650);
FORCEPROP 3 LASTPIN (2425 3650) SIG_NAME M_B_CPU1_SA_DQS_DP<4>
J 0
(2435 3660);
DISPLAY 0.659574 (2435 3660);
PAINT MONO (2435 3660);
DISPLAY INVISIBLE (2435 3660);
FORCEPROP 1 LASTPIN (2425 3650) BN 4
J 0
(2413 3658);
DISPLAY 0.680851 (2413 3658);
PAINT GREEN (2413 3658);
FORCEPROP 2 LAST CDS_LIB standard
J 0
(2475 3650);
DISPLAY INVISIBLE (2475 3650);
FORCEPROP 1 LAST BODY_TYPE PLUMBING
J 0
(2475 3700);
DISPLAY 0.872340 (2475 3700);
PAINT GREEN (2475 3700);
DISPLAY INVISIBLE (2475 3700);
FORCEPROP 1 LAST HDL_TAP TRUE
J 0
(2800 3525);
DISPLAY 0.872340 (2800 3525);
DISPLAY INVISIBLE (2800 3525);
FORCEPROP 1 LAST PATH I154
J 0
(2473 3650);
DISPLAY 0.872340 (2473 3650);
PAINT GREEN (2473 3650);
DISPLAY INVISIBLE (2473 3650);
FORCEADD TAP..1
(2475 3800);
FORCEPROP 3 LASTPIN (2425 3800) SIG_NAME M_B_CPU1_SA_DQS_DP<7>
J 0
(2435 3810);
DISPLAY 0.659574 (2435 3810);
PAINT MONO (2435 3810);
DISPLAY INVISIBLE (2435 3810);
FORCEPROP 1 LASTPIN (2425 3800) BN 7
J 0
(2413 3808);
DISPLAY 0.680851 (2413 3808);
PAINT GREEN (2413 3808);
FORCEPROP 2 LAST CDS_LIB standard
J 0
(2475 3800);
DISPLAY INVISIBLE (2475 3800);
FORCEPROP 1 LAST BODY_TYPE PLUMBING
J 0
(2475 3850);
DISPLAY 0.872340 (2475 3850);
PAINT GREEN (2475 3850);
DISPLAY INVISIBLE (2475 3850);
FORCEPROP 1 LAST HDL_TAP TRUE
J 0
(2800 3675);
DISPLAY 0.872340 (2800 3675);
DISPLAY INVISIBLE (2800 3675);
FORCEPROP 1 LAST PATH I155
J 0
(2473 3800);
DISPLAY 0.872340 (2473 3800);
PAINT GREEN (2473 3800);
DISPLAY INVISIBLE (2473 3800);
FORCEADD TAP..1
(2475 3850);
FORCEPROP 3 LASTPIN (2425 3850) SIG_NAME M_B_CPU1_SA_DQS_DP<8>
J 0
(2435 3860);
DISPLAY 0.659574 (2435 3860);
PAINT MONO (2435 3860);
DISPLAY INVISIBLE (2435 3860);
FORCEPROP 1 LASTPIN (2425 3850) BN 8
J 0
(2413 3858);
DISPLAY 0.680851 (2413 3858);
PAINT GREEN (2413 3858);
FORCEPROP 2 LAST CDS_LIB standard
J 0
(2475 3850);
DISPLAY INVISIBLE (2475 3850);
FORCEPROP 1 LAST BODY_TYPE PLUMBING
J 0
(2475 3900);
DISPLAY 0.872340 (2475 3900);
PAINT GREEN (2475 3900);
DISPLAY INVISIBLE (2475 3900);
FORCEPROP 1 LAST HDL_TAP TRUE
J 0
(2800 3725);
DISPLAY 0.872340 (2800 3725);
DISPLAY INVISIBLE (2800 3725);
FORCEPROP 1 LAST PATH I156
J 0
(2473 3850);
DISPLAY 0.872340 (2473 3850);
PAINT GREEN (2473 3850);
DISPLAY INVISIBLE (2473 3850);
FORCEADD TAP..1
(2475 3900);
FORCEPROP 3 LASTPIN (2425 3900) SIG_NAME M_B_CPU1_SA_DQS_DP<9>
J 0
(2435 3910);
DISPLAY 0.659574 (2435 3910);
PAINT MONO (2435 3910);
DISPLAY INVISIBLE (2435 3910);
FORCEPROP 1 LASTPIN (2425 3900) BN 9
J 0
(2413 3908);
DISPLAY 0.680851 (2413 3908);
PAINT GREEN (2413 3908);
FORCEPROP 2 LAST CDS_LIB standard
J 0
(2475 3900);
DISPLAY INVISIBLE (2475 3900);
FORCEPROP 1 LAST BODY_TYPE PLUMBING
J 0
(2475 3950);
DISPLAY 0.872340 (2475 3950);
PAINT GREEN (2475 3950);
DISPLAY INVISIBLE (2475 3950);
FORCEPROP 1 LAST HDL_TAP TRUE
J 0
(2800 3775);
DISPLAY 0.872340 (2800 3775);
DISPLAY INVISIBLE (2800 3775);
FORCEPROP 1 LAST PATH I157
J 0
(2473 3900);
DISPLAY 0.872340 (2473 3900);
PAINT GREEN (2473 3900);
DISPLAY INVISIBLE (2473 3900);
FORCEADD OFFPAGE..4
(3575 0);
FORCEPROP 2 LAST $XR0 101 
J 0
(3761 0);
DISPLAY 0.638298 (3761 0);
PAINT MONO (3761 0);
FORCEPROP 2 LAST CDS_LIB standard
J 0
(3575 0);
PAINT MONO (3575 0);
DISPLAY INVISIBLE (3575 0);
FORCEPROP 1 LAST OFFPAGE TRUE
J 0
(3900 -125);
DISPLAY 1.170213 (3900 -125);
PAINT GREEN (3900 -125);
DISPLAY INVISIBLE (3900 -125);
FORCEPROP 1 LAST COMMENT_BODY TRUE
J 0
(3550 -100);
DISPLAY 1.170213 (3550 -100);
PAINT GREEN (3550 -100);
DISPLAY INVISIBLE (3550 -100);
FORCEPROP 2 LAST PATH I158
J 0
(3750 75);
DISPLAY 1.021277 (3750 75);
DISPLAY INVISIBLE (3750 75);
FORCEADD OFFPAGE..2
(3575 325);
FORCEPROP 2 LAST $XR1 101 
J 0
(3884 325);
DISPLAY 0.638298 (3884 325);
PAINT MONO (3884 325);
FORCEPROP 2 LAST $XR0 100 
J 0
(3764 325);
DISPLAY 0.638298 (3764 325);
PAINT MONO (3764 325);
FORCEPROP 2 LAST CDS_LIB standard
J 0
(3575 325);
PAINT MONO (3575 325);
DISPLAY INVISIBLE (3575 325);
FORCEPROP 1 LAST OFFPAGE TRUE
J 0
(3900 200);
DISPLAY 1.170213 (3900 200);
PAINT GREEN (3900 200);
DISPLAY INVISIBLE (3900 200);
FORCEPROP 1 LAST COMMENT_BODY TRUE
J 0
(3530 230);
DISPLAY 1.170213 (3530 230);
PAINT GREEN (3530 230);
DISPLAY INVISIBLE (3530 230);
FORCEPROP 2 LAST PATH I159
J 0
(3750 400);
DISPLAY 1.021277 (3750 400);
DISPLAY INVISIBLE (3750 400);
FORCEADD TAP..1
R 2
(-950 300);
FORCEPROP 3 LASTPIN (-900 300) SIG_NAME M_B_CPU1_SB_CB<7>
J 0
(-890 310);
DISPLAY 0.659574 (-890 310);
PAINT MONO (-890 310);
DISPLAY INVISIBLE (-890 310);
FORCEPROP 1 LASTPIN (-900 300) BN 7
J 2
(-888 308);
DISPLAY 0.680851 (-888 308);
PAINT GREEN (-888 308);
FORCEPROP 2 LAST CDS_LIB standard
J 0
(-950 300);
DISPLAY INVISIBLE (-950 300);
FORCEPROP 1 LAST BODY_TYPE PLUMBING
J 2
(-950 350);
DISPLAY 0.872340 (-950 350);
PAINT GREEN (-950 350);
DISPLAY INVISIBLE (-950 350);
FORCEPROP 1 LAST HDL_TAP TRUE
J 2
(-1275 175);
DISPLAY 0.872340 (-1275 175);
DISPLAY INVISIBLE (-1275 175);
FORCEPROP 1 LAST PATH I16
J 2
(-948 300);
DISPLAY 0.872340 (-948 300);
PAINT GREEN (-948 300);
DISPLAY INVISIBLE (-948 300);
FORCEADD OFFPAGE..2
(3575 625);
FORCEPROP 2 LAST $XR1 101 
J 0
(3884 625);
DISPLAY 0.638298 (3884 625);
PAINT MONO (3884 625);
FORCEPROP 2 LAST $XR0 100 
J 0
(3764 625);
DISPLAY 0.638298 (3764 625);
PAINT MONO (3764 625);
FORCEPROP 2 LAST CDS_LIB standard
J 0
(3575 625);
PAINT MONO (3575 625);
DISPLAY INVISIBLE (3575 625);
FORCEPROP 1 LAST OFFPAGE TRUE
J 0
(3900 500);
DISPLAY 1.170213 (3900 500);
PAINT GREEN (3900 500);
DISPLAY INVISIBLE (3900 500);
FORCEPROP 1 LAST COMMENT_BODY TRUE
J 0
(3530 530);
DISPLAY 1.170213 (3530 530);
PAINT GREEN (3530 530);
DISPLAY INVISIBLE (3530 530);
FORCEPROP 2 LAST PATH I160
J 0
(3750 700);
DISPLAY 1.021277 (3750 700);
DISPLAY INVISIBLE (3750 700);
FORCEADD OFFPAGE..2
(3575 750);
FORCEPROP 2 LAST $XR1 101 
J 0
(3884 750);
DISPLAY 0.638298 (3884 750);
PAINT MONO (3884 750);
FORCEPROP 2 LAST $XR0 100 
J 0
(3764 750);
DISPLAY 0.638298 (3764 750);
PAINT MONO (3764 750);
FORCEPROP 2 LAST CDS_LIB standard
J 0
(3575 750);
PAINT MONO (3575 750);
DISPLAY INVISIBLE (3575 750);
FORCEPROP 1 LAST OFFPAGE TRUE
J 0
(3900 625);
DISPLAY 1.170213 (3900 625);
PAINT GREEN (3900 625);
DISPLAY INVISIBLE (3900 625);
FORCEPROP 1 LAST COMMENT_BODY TRUE
J 0
(3530 655);
DISPLAY 1.170213 (3530 655);
PAINT GREEN (3530 655);
DISPLAY INVISIBLE (3530 655);
FORCEPROP 2 LAST PATH I161
J 0
(3750 825);
DISPLAY 1.021277 (3750 825);
DISPLAY INVISIBLE (3750 825);
FORCEADD OFFPAGE..2
(3575 1250);
FORCEPROP 2 LAST $XR1 101 
J 0
(3884 1250);
DISPLAY 0.638298 (3884 1250);
PAINT MONO (3884 1250);
FORCEPROP 2 LAST $XR0 100 
J 0
(3764 1250);
DISPLAY 0.638298 (3764 1250);
PAINT MONO (3764 1250);
FORCEPROP 2 LAST CDS_LIB standard
J 0
(3575 1250);
PAINT MONO (3575 1250);
DISPLAY INVISIBLE (3575 1250);
FORCEPROP 1 LAST OFFPAGE TRUE
J 0
(3900 1125);
DISPLAY 1.170213 (3900 1125);
PAINT GREEN (3900 1125);
DISPLAY INVISIBLE (3900 1125);
FORCEPROP 1 LAST COMMENT_BODY TRUE
J 0
(3530 1155);
DISPLAY 1.170213 (3530 1155);
PAINT GREEN (3530 1155);
DISPLAY INVISIBLE (3530 1155);
FORCEPROP 2 LAST PATH I162
J 0
(3750 1325);
DISPLAY 1.021277 (3750 1325);
DISPLAY INVISIBLE (3750 1325);
FORCEADD OFFPAGE..3
(3575 1125);
FORCEPROP 2 LAST $XR1 101 
J 0
(3909 1125);
DISPLAY 0.638298 (3909 1125);
PAINT MONO (3909 1125);
FORCEPROP 2 LAST $XR0 100 
J 0
(3789 1125);
DISPLAY 0.638298 (3789 1125);
PAINT MONO (3789 1125);
FORCEPROP 2 LAST CDS_LIB standard
J 2
(3575 1125);
DISPLAY INVISIBLE (3575 1125);
FORCEPROP 1 LAST OFFPAGE TRUE
J 0
(3900 1000);
DISPLAY 0.872340 (3900 1000);
DISPLAY INVISIBLE (3900 1000);
FORCEPROP 1 LAST COMMENT_BODY TRUE
J 0
(3525 1025);
DISPLAY 0.872340 (3525 1025);
PAINT GREEN (3525 1025);
DISPLAY INVISIBLE (3525 1025);
FORCEPROP 2 LAST PATH I163
J 0
(3775 1200);
DISPLAY 1.021277 (3775 1200);
DISPLAY INVISIBLE (3775 1200);
FORCEADD OFFPAGE..3
(3575 1625);
FORCEPROP 2 LAST $XR1 101 
J 0
(3909 1625);
DISPLAY 0.638298 (3909 1625);
PAINT MONO (3909 1625);
FORCEPROP 2 LAST $XR0 100 
J 0
(3789 1625);
DISPLAY 0.638298 (3789 1625);
PAINT MONO (3789 1625);
FORCEPROP 2 LAST CDS_LIB standard
J 2
(3575 1625);
DISPLAY INVISIBLE (3575 1625);
FORCEPROP 1 LAST OFFPAGE TRUE
J 0
(3900 1500);
DISPLAY 0.872340 (3900 1500);
DISPLAY INVISIBLE (3900 1500);
FORCEPROP 1 LAST COMMENT_BODY TRUE
J 0
(3525 1525);
DISPLAY 0.872340 (3525 1525);
PAINT GREEN (3525 1525);
DISPLAY INVISIBLE (3525 1525);
FORCEPROP 2 LAST PATH I164
J 0
(3775 1700);
DISPLAY 1.021277 (3775 1700);
DISPLAY INVISIBLE (3775 1700);
FORCEADD OFFPAGE..3
(3575 2225);
FORCEPROP 2 LAST $XR1 101 
J 0
(3909 2225);
DISPLAY 0.638298 (3909 2225);
PAINT MONO (3909 2225);
FORCEPROP 2 LAST $XR0 100 
J 0
(3789 2225);
DISPLAY 0.638298 (3789 2225);
PAINT MONO (3789 2225);
FORCEPROP 2 LAST CDS_LIB standard
J 2
(3575 2225);
DISPLAY INVISIBLE (3575 2225);
FORCEPROP 1 LAST OFFPAGE TRUE
J 0
(3900 2100);
DISPLAY 0.872340 (3900 2100);
DISPLAY INVISIBLE (3900 2100);
FORCEPROP 1 LAST COMMENT_BODY TRUE
J 0
(3525 2125);
DISPLAY 0.872340 (3525 2125);
PAINT GREEN (3525 2125);
DISPLAY INVISIBLE (3525 2125);
FORCEPROP 2 LAST PATH I165
J 0
(3775 2300);
DISPLAY 1.021277 (3775 2300);
DISPLAY INVISIBLE (3775 2300);
FORCEADD OFFPAGE..3
(3575 2775);
FORCEPROP 2 LAST $XR1 101 
J 0
(3909 2775);
DISPLAY 0.638298 (3909 2775);
PAINT MONO (3909 2775);
FORCEPROP 2 LAST $XR0 100 
J 0
(3789 2775);
DISPLAY 0.638298 (3789 2775);
PAINT MONO (3789 2775);
FORCEPROP 2 LAST CDS_LIB standard
J 2
(3575 2775);
DISPLAY INVISIBLE (3575 2775);
FORCEPROP 1 LAST OFFPAGE TRUE
J 0
(3900 2650);
DISPLAY 0.872340 (3900 2650);
DISPLAY INVISIBLE (3900 2650);
FORCEPROP 1 LAST COMMENT_BODY TRUE
J 0
(3525 2675);
DISPLAY 0.872340 (3525 2675);
PAINT GREEN (3525 2675);
DISPLAY INVISIBLE (3525 2675);
FORCEPROP 2 LAST PATH I166
J 0
(3775 2850);
DISPLAY 1.021277 (3775 2850);
DISPLAY INVISIBLE (3775 2850);
FORCEADD OFFPAGE..3
(3575 3375);
FORCEPROP 2 LAST $XR1 101 
J 0
(3909 3375);
DISPLAY 0.638298 (3909 3375);
PAINT MONO (3909 3375);
FORCEPROP 2 LAST $XR0 100 
J 0
(3789 3375);
DISPLAY 0.638298 (3789 3375);
PAINT MONO (3789 3375);
FORCEPROP 2 LAST CDS_LIB standard
J 2
(3575 3375);
DISPLAY INVISIBLE (3575 3375);
FORCEPROP 1 LAST OFFPAGE TRUE
J 0
(3900 3250);
DISPLAY 0.872340 (3900 3250);
DISPLAY INVISIBLE (3900 3250);
FORCEPROP 1 LAST COMMENT_BODY TRUE
J 0
(3525 3275);
DISPLAY 0.872340 (3525 3275);
PAINT GREEN (3525 3275);
DISPLAY INVISIBLE (3525 3275);
FORCEPROP 2 LAST PATH I167
J 0
(3775 3450);
DISPLAY 1.021277 (3775 3450);
DISPLAY INVISIBLE (3775 3450);
FORCEADD OFFPAGE..3
(3575 3925);
FORCEPROP 2 LAST $XR1 101 
J 0
(3909 3925);
DISPLAY 0.638298 (3909 3925);
PAINT MONO (3909 3925);
FORCEPROP 2 LAST $XR0 100 
J 0
(3789 3925);
DISPLAY 0.638298 (3789 3925);
PAINT MONO (3789 3925);
FORCEPROP 2 LAST CDS_LIB standard
J 2
(3575 3925);
DISPLAY INVISIBLE (3575 3925);
FORCEPROP 1 LAST OFFPAGE TRUE
J 0
(3900 3800);
DISPLAY 0.872340 (3900 3800);
DISPLAY INVISIBLE (3900 3800);
FORCEPROP 1 LAST COMMENT_BODY TRUE
J 0
(3525 3825);
DISPLAY 0.872340 (3525 3825);
PAINT GREEN (3525 3825);
DISPLAY INVISIBLE (3525 3825);
FORCEPROP 2 LAST PATH I168
J 0
(3775 4000);
DISPLAY 1.021277 (3775 4000);
DISPLAY INVISIBLE (3775 4000);
FORCEADD TAP..1
R 2
(-950 350);
FORCEPROP 3 LASTPIN (-900 350) SIG_NAME M_B_CPU1_SB_DQ<0>
J 0
(-890 360);
DISPLAY 0.659574 (-890 360);
PAINT MONO (-890 360);
DISPLAY INVISIBLE (-890 360);
FORCEPROP 1 LASTPIN (-900 350) BN 0
J 2
(-888 358);
DISPLAY 0.680851 (-888 358);
PAINT GREEN (-888 358);
FORCEPROP 2 LAST CDS_LIB standard
J 0
(-950 350);
DISPLAY INVISIBLE (-950 350);
FORCEPROP 1 LAST BODY_TYPE PLUMBING
J 2
(-950 400);
DISPLAY 0.872340 (-950 400);
PAINT GREEN (-950 400);
DISPLAY INVISIBLE (-950 400);
FORCEPROP 1 LAST HDL_TAP TRUE
J 2
(-1275 225);
DISPLAY 0.872340 (-1275 225);
DISPLAY INVISIBLE (-1275 225);
FORCEPROP 1 LAST PATH I17
J 2
(-948 350);
DISPLAY 0.872340 (-948 350);
PAINT GREEN (-948 350);
DISPLAY INVISIBLE (-948 350);
FORCEADD TAP..1
R 2
(-950 400);
FORCEPROP 3 LASTPIN (-900 400) SIG_NAME M_B_CPU1_SB_DQ<1>
J 0
(-890 410);
DISPLAY 0.659574 (-890 410);
PAINT MONO (-890 410);
DISPLAY INVISIBLE (-890 410);
FORCEPROP 1 LASTPIN (-900 400) BN 1
J 2
(-888 408);
DISPLAY 0.680851 (-888 408);
PAINT GREEN (-888 408);
FORCEPROP 2 LAST CDS_LIB standard
J 0
(-950 400);
DISPLAY INVISIBLE (-950 400);
FORCEPROP 1 LAST BODY_TYPE PLUMBING
J 2
(-950 450);
DISPLAY 0.872340 (-950 450);
PAINT GREEN (-950 450);
DISPLAY INVISIBLE (-950 450);
FORCEPROP 1 LAST HDL_TAP TRUE
J 2
(-1275 275);
DISPLAY 0.872340 (-1275 275);
DISPLAY INVISIBLE (-1275 275);
FORCEPROP 1 LAST PATH I18
J 2
(-948 400);
DISPLAY 0.872340 (-948 400);
PAINT GREEN (-948 400);
DISPLAY INVISIBLE (-948 400);
FORCEADD TAP..1
R 2
(-950 450);
FORCEPROP 3 LASTPIN (-900 450) SIG_NAME M_B_CPU1_SB_DQ<2>
J 0
(-890 460);
DISPLAY 0.659574 (-890 460);
PAINT MONO (-890 460);
DISPLAY INVISIBLE (-890 460);
FORCEPROP 1 LASTPIN (-900 450) BN 2
J 2
(-888 458);
DISPLAY 0.680851 (-888 458);
PAINT GREEN (-888 458);
FORCEPROP 2 LAST CDS_LIB standard
J 0
(-950 450);
DISPLAY INVISIBLE (-950 450);
FORCEPROP 1 LAST BODY_TYPE PLUMBING
J 2
(-950 500);
DISPLAY 0.872340 (-950 500);
PAINT GREEN (-950 500);
DISPLAY INVISIBLE (-950 500);
FORCEPROP 1 LAST HDL_TAP TRUE
J 2
(-1275 325);
DISPLAY 0.872340 (-1275 325);
DISPLAY INVISIBLE (-1275 325);
FORCEPROP 1 LAST PATH I19
J 2
(-948 450);
DISPLAY 0.872340 (-948 450);
PAINT GREEN (-948 450);
DISPLAY INVISIBLE (-948 450);
FORCEADD OFFPAGE..2
R 2
(-1975 -225);
FORCEPROP 2 LAST $XR1 101 
J 0
(-2350 -225);
DISPLAY 0.638298 (-2350 -225);
PAINT MONO (-2350 -225);
FORCEPROP 2 LAST $XR0 100 
J 0
(-2230 -225);
DISPLAY 0.638298 (-2230 -225);
PAINT MONO (-2230 -225);
FORCEPROP 2 LAST CDS_LIB standard
J 0
(-1975 -225);
PAINT MONO (-1975 -225);
DISPLAY INVISIBLE (-1975 -225);
FORCEPROP 1 LAST OFFPAGE TRUE
J 2
(-2300 -350);
DISPLAY 0.872340 (-2300 -350);
DISPLAY INVISIBLE (-2300 -350);
FORCEPROP 1 LAST COMMENT_BODY TRUE
J 2
(-1930 -320);
DISPLAY 0.872340 (-1930 -320);
PAINT GREEN (-1930 -320);
DISPLAY INVISIBLE (-1930 -320);
FORCEPROP 2 LAST PATH I2
J 0
(-1925 -150);
DISPLAY 1.021277 (-1925 -150);
DISPLAY INVISIBLE (-1925 -150);
FORCEADD TAP..1
R 2
(-950 500);
FORCEPROP 3 LASTPIN (-900 500) SIG_NAME M_B_CPU1_SB_DQ<3>
J 0
(-890 510);
DISPLAY 0.659574 (-890 510);
PAINT MONO (-890 510);
DISPLAY INVISIBLE (-890 510);
FORCEPROP 1 LASTPIN (-900 500) BN 3
J 2
(-888 508);
DISPLAY 0.680851 (-888 508);
PAINT GREEN (-888 508);
FORCEPROP 2 LAST CDS_LIB standard
J 0
(-950 500);
DISPLAY INVISIBLE (-950 500);
FORCEPROP 1 LAST BODY_TYPE PLUMBING
J 2
(-950 550);
DISPLAY 0.872340 (-950 550);
PAINT GREEN (-950 550);
DISPLAY INVISIBLE (-950 550);
FORCEPROP 1 LAST HDL_TAP TRUE
J 2
(-1275 375);
DISPLAY 0.872340 (-1275 375);
DISPLAY INVISIBLE (-1275 375);
FORCEPROP 1 LAST PATH I20
J 2
(-948 500);
DISPLAY 0.872340 (-948 500);
PAINT GREEN (-948 500);
DISPLAY INVISIBLE (-948 500);
FORCEADD TAP..1
R 2
(-950 550);
FORCEPROP 3 LASTPIN (-900 550) SIG_NAME M_B_CPU1_SB_DQ<4>
J 0
(-890 560);
DISPLAY 0.659574 (-890 560);
PAINT MONO (-890 560);
DISPLAY INVISIBLE (-890 560);
FORCEPROP 1 LASTPIN (-900 550) BN 4
J 2
(-888 558);
DISPLAY 0.680851 (-888 558);
PAINT GREEN (-888 558);
FORCEPROP 2 LAST CDS_LIB standard
J 0
(-950 550);
DISPLAY INVISIBLE (-950 550);
FORCEPROP 1 LAST BODY_TYPE PLUMBING
J 2
(-950 600);
DISPLAY 0.872340 (-950 600);
PAINT GREEN (-950 600);
DISPLAY INVISIBLE (-950 600);
FORCEPROP 1 LAST HDL_TAP TRUE
J 2
(-1275 425);
DISPLAY 0.872340 (-1275 425);
DISPLAY INVISIBLE (-1275 425);
FORCEPROP 1 LAST PATH I21
J 2
(-948 550);
DISPLAY 0.872340 (-948 550);
PAINT GREEN (-948 550);
DISPLAY INVISIBLE (-948 550);
FORCEADD TAP..1
R 2
(-950 650);
FORCEPROP 3 LASTPIN (-900 650) SIG_NAME M_B_CPU1_SB_DQ<6>
J 0
(-890 660);
DISPLAY 0.659574 (-890 660);
PAINT MONO (-890 660);
DISPLAY INVISIBLE (-890 660);
FORCEPROP 1 LASTPIN (-900 650) BN 6
J 2
(-888 658);
DISPLAY 0.680851 (-888 658);
PAINT GREEN (-888 658);
FORCEPROP 2 LAST CDS_LIB standard
J 0
(-950 650);
DISPLAY INVISIBLE (-950 650);
FORCEPROP 1 LAST BODY_TYPE PLUMBING
J 2
(-950 700);
DISPLAY 0.872340 (-950 700);
PAINT GREEN (-950 700);
DISPLAY INVISIBLE (-950 700);
FORCEPROP 1 LAST HDL_TAP TRUE
J 2
(-1275 525);
DISPLAY 0.872340 (-1275 525);
DISPLAY INVISIBLE (-1275 525);
FORCEPROP 1 LAST PATH I22
J 2
(-948 650);
DISPLAY 0.872340 (-948 650);
PAINT GREEN (-948 650);
DISPLAY INVISIBLE (-948 650);
FORCEADD TAP..1
R 2
(-950 600);
FORCEPROP 3 LASTPIN (-900 600) SIG_NAME M_B_CPU1_SB_DQ<5>
J 0
(-890 610);
DISPLAY 0.659574 (-890 610);
PAINT MONO (-890 610);
DISPLAY INVISIBLE (-890 610);
FORCEPROP 1 LASTPIN (-900 600) BN 5
J 2
(-888 608);
DISPLAY 0.680851 (-888 608);
PAINT GREEN (-888 608);
FORCEPROP 2 LAST CDS_LIB standard
J 0
(-950 600);
DISPLAY INVISIBLE (-950 600);
FORCEPROP 1 LAST BODY_TYPE PLUMBING
J 2
(-950 650);
DISPLAY 0.872340 (-950 650);
PAINT GREEN (-950 650);
DISPLAY INVISIBLE (-950 650);
FORCEPROP 1 LAST HDL_TAP TRUE
J 2
(-1275 475);
DISPLAY 0.872340 (-1275 475);
DISPLAY INVISIBLE (-1275 475);
FORCEPROP 1 LAST PATH I23
J 2
(-948 600);
DISPLAY 0.872340 (-948 600);
PAINT GREEN (-948 600);
DISPLAY INVISIBLE (-948 600);
FORCEADD TAP..1
R 2
(-950 700);
FORCEPROP 3 LASTPIN (-900 700) SIG_NAME M_B_CPU1_SB_DQ<7>
J 0
(-890 710);
DISPLAY 0.659574 (-890 710);
PAINT MONO (-890 710);
DISPLAY INVISIBLE (-890 710);
FORCEPROP 1 LASTPIN (-900 700) BN 7
J 2
(-888 708);
DISPLAY 0.680851 (-888 708);
PAINT GREEN (-888 708);
FORCEPROP 2 LAST CDS_LIB standard
J 0
(-950 700);
DISPLAY INVISIBLE (-950 700);
FORCEPROP 1 LAST BODY_TYPE PLUMBING
J 2
(-950 750);
DISPLAY 0.872340 (-950 750);
PAINT GREEN (-950 750);
DISPLAY INVISIBLE (-950 750);
FORCEPROP 1 LAST HDL_TAP TRUE
J 2
(-1275 575);
DISPLAY 0.872340 (-1275 575);
DISPLAY INVISIBLE (-1275 575);
FORCEPROP 1 LAST PATH I24
J 2
(-948 700);
DISPLAY 0.872340 (-948 700);
PAINT GREEN (-948 700);
DISPLAY INVISIBLE (-948 700);
FORCEADD TAP..1
R 2
(-950 750);
FORCEPROP 3 LASTPIN (-900 750) SIG_NAME M_B_CPU1_SB_DQ<8>
J 0
(-890 760);
DISPLAY 0.659574 (-890 760);
PAINT MONO (-890 760);
DISPLAY INVISIBLE (-890 760);
FORCEPROP 1 LASTPIN (-900 750) BN 8
J 2
(-888 758);
DISPLAY 0.680851 (-888 758);
PAINT GREEN (-888 758);
FORCEPROP 2 LAST CDS_LIB standard
J 0
(-950 750);
DISPLAY INVISIBLE (-950 750);
FORCEPROP 1 LAST BODY_TYPE PLUMBING
J 2
(-950 800);
DISPLAY 0.872340 (-950 800);
PAINT GREEN (-950 800);
DISPLAY INVISIBLE (-950 800);
FORCEPROP 1 LAST HDL_TAP TRUE
J 2
(-1275 625);
DISPLAY 0.872340 (-1275 625);
DISPLAY INVISIBLE (-1275 625);
FORCEPROP 1 LAST PATH I25
J 2
(-948 750);
DISPLAY 0.872340 (-948 750);
PAINT GREEN (-948 750);
DISPLAY INVISIBLE (-948 750);
FORCEADD TAP..1
R 2
(-950 800);
FORCEPROP 3 LASTPIN (-900 800) SIG_NAME M_B_CPU1_SB_DQ<9>
J 0
(-890 810);
DISPLAY 0.659574 (-890 810);
PAINT MONO (-890 810);
DISPLAY INVISIBLE (-890 810);
FORCEPROP 1 LASTPIN (-900 800) BN 9
J 2
(-888 808);
DISPLAY 0.680851 (-888 808);
PAINT GREEN (-888 808);
FORCEPROP 2 LAST CDS_LIB standard
J 0
(-950 800);
DISPLAY INVISIBLE (-950 800);
FORCEPROP 1 LAST BODY_TYPE PLUMBING
J 2
(-950 850);
DISPLAY 0.872340 (-950 850);
PAINT GREEN (-950 850);
DISPLAY INVISIBLE (-950 850);
FORCEPROP 1 LAST HDL_TAP TRUE
J 2
(-1275 675);
DISPLAY 0.872340 (-1275 675);
DISPLAY INVISIBLE (-1275 675);
FORCEPROP 1 LAST PATH I26
J 2
(-948 800);
DISPLAY 0.872340 (-948 800);
PAINT GREEN (-948 800);
DISPLAY INVISIBLE (-948 800);
FORCEADD TAP..1
R 2
(-950 850);
FORCEPROP 3 LASTPIN (-900 850) SIG_NAME M_B_CPU1_SB_DQ<10>
J 0
(-890 860);
DISPLAY 0.659574 (-890 860);
PAINT MONO (-890 860);
DISPLAY INVISIBLE (-890 860);
FORCEPROP 1 LASTPIN (-900 850) BN 10
J 2
(-888 858);
DISPLAY 0.680851 (-888 858);
PAINT GREEN (-888 858);
FORCEPROP 2 LAST CDS_LIB standard
J 0
(-950 850);
DISPLAY INVISIBLE (-950 850);
FORCEPROP 1 LAST BODY_TYPE PLUMBING
J 2
(-950 900);
DISPLAY 0.872340 (-950 900);
PAINT GREEN (-950 900);
DISPLAY INVISIBLE (-950 900);
FORCEPROP 1 LAST HDL_TAP TRUE
J 2
(-1275 725);
DISPLAY 0.872340 (-1275 725);
DISPLAY INVISIBLE (-1275 725);
FORCEPROP 1 LAST PATH I27
J 2
(-948 850);
DISPLAY 0.872340 (-948 850);
PAINT GREEN (-948 850);
DISPLAY INVISIBLE (-948 850);
FORCEADD TAP..1
R 2
(-950 900);
FORCEPROP 3 LASTPIN (-900 900) SIG_NAME M_B_CPU1_SB_DQ<11>
J 0
(-890 910);
DISPLAY 0.659574 (-890 910);
PAINT MONO (-890 910);
DISPLAY INVISIBLE (-890 910);
FORCEPROP 1 LASTPIN (-900 900) BN 11
J 2
(-888 908);
DISPLAY 0.680851 (-888 908);
PAINT GREEN (-888 908);
FORCEPROP 2 LAST CDS_LIB standard
J 0
(-950 900);
DISPLAY INVISIBLE (-950 900);
FORCEPROP 1 LAST BODY_TYPE PLUMBING
J 2
(-950 950);
DISPLAY 0.872340 (-950 950);
PAINT GREEN (-950 950);
DISPLAY INVISIBLE (-950 950);
FORCEPROP 1 LAST HDL_TAP TRUE
J 2
(-1275 775);
DISPLAY 0.872340 (-1275 775);
DISPLAY INVISIBLE (-1275 775);
FORCEPROP 1 LAST PATH I28
J 2
(-948 900);
DISPLAY 0.872340 (-948 900);
PAINT GREEN (-948 900);
DISPLAY INVISIBLE (-948 900);
FORCEADD TAP..1
R 2
(-950 950);
FORCEPROP 3 LASTPIN (-900 950) SIG_NAME M_B_CPU1_SB_DQ<12>
J 0
(-890 960);
DISPLAY 0.659574 (-890 960);
PAINT MONO (-890 960);
DISPLAY INVISIBLE (-890 960);
FORCEPROP 1 LASTPIN (-900 950) BN 12
J 2
(-888 958);
DISPLAY 0.680851 (-888 958);
PAINT GREEN (-888 958);
FORCEPROP 2 LAST CDS_LIB standard
J 0
(-950 950);
DISPLAY INVISIBLE (-950 950);
FORCEPROP 1 LAST BODY_TYPE PLUMBING
J 2
(-950 1000);
DISPLAY 0.872340 (-950 1000);
PAINT GREEN (-950 1000);
DISPLAY INVISIBLE (-950 1000);
FORCEPROP 1 LAST HDL_TAP TRUE
J 2
(-1275 825);
DISPLAY 0.872340 (-1275 825);
DISPLAY INVISIBLE (-1275 825);
FORCEPROP 1 LAST PATH I29
J 2
(-948 950);
DISPLAY 0.872340 (-948 950);
PAINT GREEN (-948 950);
DISPLAY INVISIBLE (-948 950);
FORCEADD TAP..1
R 2
(-950 -300);
FORCEPROP 3 LASTPIN (-900 -300) SIG_NAME M_B_CPU1_CLK_DN<0>
J 0
(-890 -290);
DISPLAY 0.659574 (-890 -290);
PAINT MONO (-890 -290);
DISPLAY INVISIBLE (-890 -290);
FORCEPROP 1 LASTPIN (-900 -300) BN 0
J 2
(-888 -292);
DISPLAY 0.680851 (-888 -292);
PAINT GREEN (-888 -292);
FORCEPROP 2 LAST CDS_LIB standard
J 0
(-950 -300);
DISPLAY INVISIBLE (-950 -300);
FORCEPROP 1 LAST BODY_TYPE PLUMBING
J 2
(-950 -250);
DISPLAY 0.872340 (-950 -250);
PAINT GREEN (-950 -250);
DISPLAY INVISIBLE (-950 -250);
FORCEPROP 1 LAST HDL_TAP TRUE
J 2
(-1275 -425);
DISPLAY 0.872340 (-1275 -425);
DISPLAY INVISIBLE (-1275 -425);
FORCEPROP 1 LAST PATH I3
J 2
(-948 -300);
DISPLAY 0.872340 (-948 -300);
PAINT GREEN (-948 -300);
DISPLAY INVISIBLE (-948 -300);
FORCEADD TAP..1
R 2
(-950 1050);
FORCEPROP 3 LASTPIN (-900 1050) SIG_NAME M_B_CPU1_SB_DQ<14>
J 0
(-890 1060);
DISPLAY 0.659574 (-890 1060);
PAINT MONO (-890 1060);
DISPLAY INVISIBLE (-890 1060);
FORCEPROP 1 LASTPIN (-900 1050) BN 14
J 2
(-888 1058);
DISPLAY 0.680851 (-888 1058);
PAINT GREEN (-888 1058);
FORCEPROP 2 LAST CDS_LIB standard
J 0
(-950 1050);
DISPLAY INVISIBLE (-950 1050);
FORCEPROP 1 LAST BODY_TYPE PLUMBING
J 2
(-950 1100);
DISPLAY 0.872340 (-950 1100);
PAINT GREEN (-950 1100);
DISPLAY INVISIBLE (-950 1100);
FORCEPROP 1 LAST HDL_TAP TRUE
J 2
(-1275 925);
DISPLAY 0.872340 (-1275 925);
DISPLAY INVISIBLE (-1275 925);
FORCEPROP 1 LAST PATH I30
J 2
(-948 1050);
DISPLAY 0.872340 (-948 1050);
PAINT GREEN (-948 1050);
DISPLAY INVISIBLE (-948 1050);
FORCEADD TAP..1
R 2
(-950 1000);
FORCEPROP 3 LASTPIN (-900 1000) SIG_NAME M_B_CPU1_SB_DQ<13>
J 0
(-890 1010);
DISPLAY 0.659574 (-890 1010);
PAINT MONO (-890 1010);
DISPLAY INVISIBLE (-890 1010);
FORCEPROP 1 LASTPIN (-900 1000) BN 13
J 2
(-888 1008);
DISPLAY 0.680851 (-888 1008);
PAINT GREEN (-888 1008);
FORCEPROP 2 LAST CDS_LIB standard
J 0
(-950 1000);
DISPLAY INVISIBLE (-950 1000);
FORCEPROP 1 LAST BODY_TYPE PLUMBING
J 2
(-950 1050);
DISPLAY 0.872340 (-950 1050);
PAINT GREEN (-950 1050);
DISPLAY INVISIBLE (-950 1050);
FORCEPROP 1 LAST HDL_TAP TRUE
J 2
(-1275 875);
DISPLAY 0.872340 (-1275 875);
DISPLAY INVISIBLE (-1275 875);
FORCEPROP 1 LAST PATH I31
J 2
(-948 1000);
DISPLAY 0.872340 (-948 1000);
PAINT GREEN (-948 1000);
DISPLAY INVISIBLE (-948 1000);
FORCEADD TAP..1
R 2
(-950 1100);
FORCEPROP 3 LASTPIN (-900 1100) SIG_NAME M_B_CPU1_SB_DQ<15>
J 0
(-890 1110);
DISPLAY 0.659574 (-890 1110);
PAINT MONO (-890 1110);
DISPLAY INVISIBLE (-890 1110);
FORCEPROP 1 LASTPIN (-900 1100) BN 15
J 2
(-888 1108);
DISPLAY 0.680851 (-888 1108);
PAINT GREEN (-888 1108);
FORCEPROP 2 LAST CDS_LIB standard
J 0
(-950 1100);
DISPLAY INVISIBLE (-950 1100);
FORCEPROP 1 LAST BODY_TYPE PLUMBING
J 2
(-950 1150);
DISPLAY 0.872340 (-950 1150);
PAINT GREEN (-950 1150);
DISPLAY INVISIBLE (-950 1150);
FORCEPROP 1 LAST HDL_TAP TRUE
J 2
(-1275 975);
DISPLAY 0.872340 (-1275 975);
DISPLAY INVISIBLE (-1275 975);
FORCEPROP 1 LAST PATH I32
J 2
(-948 1100);
DISPLAY 0.872340 (-948 1100);
PAINT GREEN (-948 1100);
DISPLAY INVISIBLE (-948 1100);
FORCEADD TAP..1
R 2
(-950 1150);
FORCEPROP 3 LASTPIN (-900 1150) SIG_NAME M_B_CPU1_SB_DQ<16>
J 0
(-890 1160);
DISPLAY 0.659574 (-890 1160);
PAINT MONO (-890 1160);
DISPLAY INVISIBLE (-890 1160);
FORCEPROP 1 LASTPIN (-900 1150) BN 16
J 2
(-888 1158);
DISPLAY 0.680851 (-888 1158);
PAINT GREEN (-888 1158);
FORCEPROP 2 LAST CDS_LIB standard
J 0
(-950 1150);
DISPLAY INVISIBLE (-950 1150);
FORCEPROP 1 LAST BODY_TYPE PLUMBING
J 2
(-950 1200);
DISPLAY 0.872340 (-950 1200);
PAINT GREEN (-950 1200);
DISPLAY INVISIBLE (-950 1200);
FORCEPROP 1 LAST HDL_TAP TRUE
J 2
(-1275 1025);
DISPLAY 0.872340 (-1275 1025);
DISPLAY INVISIBLE (-1275 1025);
FORCEPROP 1 LAST PATH I33
J 2
(-948 1150);
DISPLAY 0.872340 (-948 1150);
PAINT GREEN (-948 1150);
DISPLAY INVISIBLE (-948 1150);
FORCEADD TAP..1
R 2
(-950 1200);
FORCEPROP 3 LASTPIN (-900 1200) SIG_NAME M_B_CPU1_SB_DQ<17>
J 0
(-890 1210);
DISPLAY 0.659574 (-890 1210);
PAINT MONO (-890 1210);
DISPLAY INVISIBLE (-890 1210);
FORCEPROP 1 LASTPIN (-900 1200) BN 17
J 2
(-888 1208);
DISPLAY 0.680851 (-888 1208);
PAINT GREEN (-888 1208);
FORCEPROP 2 LAST CDS_LIB standard
J 0
(-950 1200);
DISPLAY INVISIBLE (-950 1200);
FORCEPROP 1 LAST BODY_TYPE PLUMBING
J 2
(-950 1250);
DISPLAY 0.872340 (-950 1250);
PAINT GREEN (-950 1250);
DISPLAY INVISIBLE (-950 1250);
FORCEPROP 1 LAST HDL_TAP TRUE
J 2
(-1275 1075);
DISPLAY 0.872340 (-1275 1075);
DISPLAY INVISIBLE (-1275 1075);
FORCEPROP 1 LAST PATH I34
J 2
(-948 1200);
DISPLAY 0.872340 (-948 1200);
PAINT GREEN (-948 1200);
DISPLAY INVISIBLE (-948 1200);
FORCEADD TAP..1
R 2
(-950 1300);
FORCEPROP 3 LASTPIN (-900 1300) SIG_NAME M_B_CPU1_SB_DQ<19>
J 0
(-890 1310);
DISPLAY 0.659574 (-890 1310);
PAINT MONO (-890 1310);
DISPLAY INVISIBLE (-890 1310);
FORCEPROP 1 LASTPIN (-900 1300) BN 19
J 2
(-888 1308);
DISPLAY 0.680851 (-888 1308);
PAINT GREEN (-888 1308);
FORCEPROP 2 LAST CDS_LIB standard
J 0
(-950 1300);
DISPLAY INVISIBLE (-950 1300);
FORCEPROP 1 LAST BODY_TYPE PLUMBING
J 2
(-950 1350);
DISPLAY 0.872340 (-950 1350);
PAINT GREEN (-950 1350);
DISPLAY INVISIBLE (-950 1350);
FORCEPROP 1 LAST HDL_TAP TRUE
J 2
(-1275 1175);
DISPLAY 0.872340 (-1275 1175);
DISPLAY INVISIBLE (-1275 1175);
FORCEPROP 1 LAST PATH I35
J 2
(-948 1300);
DISPLAY 0.872340 (-948 1300);
PAINT GREEN (-948 1300);
DISPLAY INVISIBLE (-948 1300);
FORCEADD TAP..1
R 2
(-950 1250);
FORCEPROP 3 LASTPIN (-900 1250) SIG_NAME M_B_CPU1_SB_DQ<18>
J 0
(-890 1260);
DISPLAY 0.659574 (-890 1260);
PAINT MONO (-890 1260);
DISPLAY INVISIBLE (-890 1260);
FORCEPROP 1 LASTPIN (-900 1250) BN 18
J 2
(-888 1258);
DISPLAY 0.680851 (-888 1258);
PAINT GREEN (-888 1258);
FORCEPROP 2 LAST CDS_LIB standard
J 0
(-950 1250);
DISPLAY INVISIBLE (-950 1250);
FORCEPROP 1 LAST BODY_TYPE PLUMBING
J 2
(-950 1300);
DISPLAY 0.872340 (-950 1300);
PAINT GREEN (-950 1300);
DISPLAY INVISIBLE (-950 1300);
FORCEPROP 1 LAST HDL_TAP TRUE
J 2
(-1275 1125);
DISPLAY 0.872340 (-1275 1125);
DISPLAY INVISIBLE (-1275 1125);
FORCEPROP 1 LAST PATH I36
J 2
(-948 1250);
DISPLAY 0.872340 (-948 1250);
PAINT GREEN (-948 1250);
DISPLAY INVISIBLE (-948 1250);
FORCEADD TAP..1
R 2
(-950 1350);
FORCEPROP 3 LASTPIN (-900 1350) SIG_NAME M_B_CPU1_SB_DQ<20>
J 0
(-890 1360);
DISPLAY 0.659574 (-890 1360);
PAINT MONO (-890 1360);
DISPLAY INVISIBLE (-890 1360);
FORCEPROP 1 LASTPIN (-900 1350) BN 20
J 2
(-888 1358);
DISPLAY 0.680851 (-888 1358);
PAINT GREEN (-888 1358);
FORCEPROP 2 LAST CDS_LIB standard
J 0
(-950 1350);
DISPLAY INVISIBLE (-950 1350);
FORCEPROP 1 LAST BODY_TYPE PLUMBING
J 2
(-950 1400);
DISPLAY 0.872340 (-950 1400);
PAINT GREEN (-950 1400);
DISPLAY INVISIBLE (-950 1400);
FORCEPROP 1 LAST HDL_TAP TRUE
J 2
(-1275 1225);
DISPLAY 0.872340 (-1275 1225);
DISPLAY INVISIBLE (-1275 1225);
FORCEPROP 1 LAST PATH I37
J 2
(-948 1350);
DISPLAY 0.872340 (-948 1350);
PAINT GREEN (-948 1350);
DISPLAY INVISIBLE (-948 1350);
FORCEADD TAP..1
R 2
(-950 1400);
FORCEPROP 3 LASTPIN (-900 1400) SIG_NAME M_B_CPU1_SB_DQ<21>
J 0
(-890 1410);
DISPLAY 0.659574 (-890 1410);
PAINT MONO (-890 1410);
DISPLAY INVISIBLE (-890 1410);
FORCEPROP 1 LASTPIN (-900 1400) BN 21
J 2
(-888 1408);
DISPLAY 0.680851 (-888 1408);
PAINT GREEN (-888 1408);
FORCEPROP 2 LAST CDS_LIB standard
J 0
(-950 1400);
DISPLAY INVISIBLE (-950 1400);
FORCEPROP 1 LAST BODY_TYPE PLUMBING
J 2
(-950 1450);
DISPLAY 0.872340 (-950 1450);
PAINT GREEN (-950 1450);
DISPLAY INVISIBLE (-950 1450);
FORCEPROP 1 LAST HDL_TAP TRUE
J 2
(-1275 1275);
DISPLAY 0.872340 (-1275 1275);
DISPLAY INVISIBLE (-1275 1275);
FORCEPROP 1 LAST PATH I38
J 2
(-948 1400);
DISPLAY 0.872340 (-948 1400);
PAINT GREEN (-948 1400);
DISPLAY INVISIBLE (-948 1400);
FORCEADD TAP..1
R 2
(-950 1450);
FORCEPROP 3 LASTPIN (-900 1450) SIG_NAME M_B_CPU1_SB_DQ<22>
J 0
(-890 1460);
DISPLAY 0.659574 (-890 1460);
PAINT MONO (-890 1460);
DISPLAY INVISIBLE (-890 1460);
FORCEPROP 1 LASTPIN (-900 1450) BN 22
J 2
(-888 1458);
DISPLAY 0.680851 (-888 1458);
PAINT GREEN (-888 1458);
FORCEPROP 2 LAST CDS_LIB standard
J 0
(-950 1450);
DISPLAY INVISIBLE (-950 1450);
FORCEPROP 1 LAST BODY_TYPE PLUMBING
J 2
(-950 1500);
DISPLAY 0.872340 (-950 1500);
PAINT GREEN (-950 1500);
DISPLAY INVISIBLE (-950 1500);
FORCEPROP 1 LAST HDL_TAP TRUE
J 2
(-1275 1325);
DISPLAY 0.872340 (-1275 1325);
DISPLAY INVISIBLE (-1275 1325);
FORCEPROP 1 LAST PATH I39
J 2
(-948 1450);
DISPLAY 0.872340 (-948 1450);
PAINT GREEN (-948 1450);
DISPLAY INVISIBLE (-948 1450);
FORCEADD TAP..1
R 2
(-950 -250);
FORCEPROP 3 LASTPIN (-900 -250) SIG_NAME M_B_CPU1_CLK_DN<1>
J 0
(-890 -240);
DISPLAY 0.659574 (-890 -240);
PAINT MONO (-890 -240);
DISPLAY INVISIBLE (-890 -240);
FORCEPROP 1 LASTPIN (-900 -250) BN 1
J 2
(-888 -242);
DISPLAY 0.680851 (-888 -242);
PAINT GREEN (-888 -242);
FORCEPROP 2 LAST CDS_LIB standard
J 0
(-950 -250);
DISPLAY INVISIBLE (-950 -250);
FORCEPROP 1 LAST BODY_TYPE PLUMBING
J 2
(-950 -200);
DISPLAY 0.872340 (-950 -200);
PAINT GREEN (-950 -200);
DISPLAY INVISIBLE (-950 -200);
FORCEPROP 1 LAST HDL_TAP TRUE
J 2
(-1275 -375);
DISPLAY 0.872340 (-1275 -375);
DISPLAY INVISIBLE (-1275 -375);
FORCEPROP 1 LAST PATH I4
J 2
(-948 -250);
DISPLAY 0.872340 (-948 -250);
PAINT GREEN (-948 -250);
DISPLAY INVISIBLE (-948 -250);
FORCEADD TAP..1
R 2
(-950 1550);
FORCEPROP 3 LASTPIN (-900 1550) SIG_NAME M_B_CPU1_SB_DQ<24>
J 0
(-890 1560);
DISPLAY 0.659574 (-890 1560);
PAINT MONO (-890 1560);
DISPLAY INVISIBLE (-890 1560);
FORCEPROP 1 LASTPIN (-900 1550) BN 24
J 2
(-888 1558);
DISPLAY 0.680851 (-888 1558);
PAINT GREEN (-888 1558);
FORCEPROP 2 LAST CDS_LIB standard
J 0
(-950 1550);
DISPLAY INVISIBLE (-950 1550);
FORCEPROP 1 LAST BODY_TYPE PLUMBING
J 2
(-950 1600);
DISPLAY 0.872340 (-950 1600);
PAINT GREEN (-950 1600);
DISPLAY INVISIBLE (-950 1600);
FORCEPROP 1 LAST HDL_TAP TRUE
J 2
(-1275 1425);
DISPLAY 0.872340 (-1275 1425);
DISPLAY INVISIBLE (-1275 1425);
FORCEPROP 1 LAST PATH I40
J 2
(-948 1550);
DISPLAY 0.872340 (-948 1550);
PAINT GREEN (-948 1550);
DISPLAY INVISIBLE (-948 1550);
FORCEADD TAP..1
R 2
(-950 1500);
FORCEPROP 3 LASTPIN (-900 1500) SIG_NAME M_B_CPU1_SB_DQ<23>
J 0
(-890 1510);
DISPLAY 0.659574 (-890 1510);
PAINT MONO (-890 1510);
DISPLAY INVISIBLE (-890 1510);
FORCEPROP 1 LASTPIN (-900 1500) BN 23
J 2
(-888 1508);
DISPLAY 0.680851 (-888 1508);
PAINT GREEN (-888 1508);
FORCEPROP 2 LAST CDS_LIB standard
J 0
(-950 1500);
DISPLAY INVISIBLE (-950 1500);
FORCEPROP 1 LAST BODY_TYPE PLUMBING
J 2
(-950 1550);
DISPLAY 0.872340 (-950 1550);
PAINT GREEN (-950 1550);
DISPLAY INVISIBLE (-950 1550);
FORCEPROP 1 LAST HDL_TAP TRUE
J 2
(-1275 1375);
DISPLAY 0.872340 (-1275 1375);
DISPLAY INVISIBLE (-1275 1375);
FORCEPROP 1 LAST PATH I41
J 2
(-948 1500);
DISPLAY 0.872340 (-948 1500);
PAINT GREEN (-948 1500);
DISPLAY INVISIBLE (-948 1500);
FORCEADD TAP..1
R 2
(-950 1600);
FORCEPROP 3 LASTPIN (-900 1600) SIG_NAME M_B_CPU1_SB_DQ<25>
J 0
(-890 1610);
DISPLAY 0.659574 (-890 1610);
PAINT MONO (-890 1610);
DISPLAY INVISIBLE (-890 1610);
FORCEPROP 1 LASTPIN (-900 1600) BN 25
J 2
(-888 1608);
DISPLAY 0.680851 (-888 1608);
PAINT GREEN (-888 1608);
FORCEPROP 2 LAST CDS_LIB standard
J 0
(-950 1600);
DISPLAY INVISIBLE (-950 1600);
FORCEPROP 1 LAST BODY_TYPE PLUMBING
J 2
(-950 1650);
DISPLAY 0.872340 (-950 1650);
PAINT GREEN (-950 1650);
DISPLAY INVISIBLE (-950 1650);
FORCEPROP 1 LAST HDL_TAP TRUE
J 2
(-1275 1475);
DISPLAY 0.872340 (-1275 1475);
DISPLAY INVISIBLE (-1275 1475);
FORCEPROP 1 LAST PATH I42
J 2
(-948 1600);
DISPLAY 0.872340 (-948 1600);
PAINT GREEN (-948 1600);
DISPLAY INVISIBLE (-948 1600);
FORCEADD TAP..1
R 2
(-950 1650);
FORCEPROP 3 LASTPIN (-900 1650) SIG_NAME M_B_CPU1_SB_DQ<26>
J 0
(-890 1660);
DISPLAY 0.659574 (-890 1660);
PAINT MONO (-890 1660);
DISPLAY INVISIBLE (-890 1660);
FORCEPROP 1 LASTPIN (-900 1650) BN 26
J 2
(-888 1658);
DISPLAY 0.680851 (-888 1658);
PAINT GREEN (-888 1658);
FORCEPROP 2 LAST CDS_LIB standard
J 0
(-950 1650);
DISPLAY INVISIBLE (-950 1650);
FORCEPROP 1 LAST BODY_TYPE PLUMBING
J 2
(-950 1700);
DISPLAY 0.872340 (-950 1700);
PAINT GREEN (-950 1700);
DISPLAY INVISIBLE (-950 1700);
FORCEPROP 1 LAST HDL_TAP TRUE
J 2
(-1275 1525);
DISPLAY 0.872340 (-1275 1525);
DISPLAY INVISIBLE (-1275 1525);
FORCEPROP 1 LAST PATH I43
J 2
(-948 1650);
DISPLAY 0.872340 (-948 1650);
PAINT GREEN (-948 1650);
DISPLAY INVISIBLE (-948 1650);
FORCEADD TAP..1
R 2
(-950 1700);
FORCEPROP 3 LASTPIN (-900 1700) SIG_NAME M_B_CPU1_SB_DQ<27>
J 0
(-890 1710);
DISPLAY 0.659574 (-890 1710);
PAINT MONO (-890 1710);
DISPLAY INVISIBLE (-890 1710);
FORCEPROP 1 LASTPIN (-900 1700) BN 27
J 2
(-888 1708);
DISPLAY 0.680851 (-888 1708);
PAINT GREEN (-888 1708);
FORCEPROP 2 LAST CDS_LIB standard
J 0
(-950 1700);
DISPLAY INVISIBLE (-950 1700);
FORCEPROP 1 LAST BODY_TYPE PLUMBING
J 2
(-950 1750);
DISPLAY 0.872340 (-950 1750);
PAINT GREEN (-950 1750);
DISPLAY INVISIBLE (-950 1750);
FORCEPROP 1 LAST HDL_TAP TRUE
J 2
(-1275 1575);
DISPLAY 0.872340 (-1275 1575);
DISPLAY INVISIBLE (-1275 1575);
FORCEPROP 1 LAST PATH I44
J 2
(-948 1700);
DISPLAY 0.872340 (-948 1700);
PAINT GREEN (-948 1700);
DISPLAY INVISIBLE (-948 1700);
FORCEADD TAP..1
R 2
(-950 1750);
FORCEPROP 3 LASTPIN (-900 1750) SIG_NAME M_B_CPU1_SB_DQ<28>
J 0
(-890 1760);
DISPLAY 0.659574 (-890 1760);
PAINT MONO (-890 1760);
DISPLAY INVISIBLE (-890 1760);
FORCEPROP 1 LASTPIN (-900 1750) BN 28
J 2
(-888 1758);
DISPLAY 0.680851 (-888 1758);
PAINT GREEN (-888 1758);
FORCEPROP 2 LAST CDS_LIB standard
J 0
(-950 1750);
DISPLAY INVISIBLE (-950 1750);
FORCEPROP 1 LAST BODY_TYPE PLUMBING
J 2
(-950 1800);
DISPLAY 0.872340 (-950 1800);
PAINT GREEN (-950 1800);
DISPLAY INVISIBLE (-950 1800);
FORCEPROP 1 LAST HDL_TAP TRUE
J 2
(-1275 1625);
DISPLAY 0.872340 (-1275 1625);
DISPLAY INVISIBLE (-1275 1625);
FORCEPROP 1 LAST PATH I45
J 2
(-948 1750);
DISPLAY 0.872340 (-948 1750);
PAINT GREEN (-948 1750);
DISPLAY INVISIBLE (-948 1750);
FORCEADD TAP..1
R 2
(-950 1800);
FORCEPROP 3 LASTPIN (-900 1800) SIG_NAME M_B_CPU1_SB_DQ<29>
J 0
(-890 1810);
DISPLAY 0.659574 (-890 1810);
PAINT MONO (-890 1810);
DISPLAY INVISIBLE (-890 1810);
FORCEPROP 1 LASTPIN (-900 1800) BN 29
J 2
(-888 1808);
DISPLAY 0.680851 (-888 1808);
PAINT GREEN (-888 1808);
FORCEPROP 2 LAST CDS_LIB standard
J 0
(-950 1800);
DISPLAY INVISIBLE (-950 1800);
FORCEPROP 1 LAST BODY_TYPE PLUMBING
J 2
(-950 1850);
DISPLAY 0.872340 (-950 1850);
PAINT GREEN (-950 1850);
DISPLAY INVISIBLE (-950 1850);
FORCEPROP 1 LAST HDL_TAP TRUE
J 2
(-1275 1675);
DISPLAY 0.872340 (-1275 1675);
DISPLAY INVISIBLE (-1275 1675);
FORCEPROP 1 LAST PATH I46
J 2
(-948 1800);
DISPLAY 0.872340 (-948 1800);
PAINT GREEN (-948 1800);
DISPLAY INVISIBLE (-948 1800);
FORCEADD TAP..1
R 2
(-950 1900);
FORCEPROP 3 LASTPIN (-900 1900) SIG_NAME M_B_CPU1_SB_DQ<31>
J 0
(-890 1910);
DISPLAY 0.659574 (-890 1910);
PAINT MONO (-890 1910);
DISPLAY INVISIBLE (-890 1910);
FORCEPROP 1 LASTPIN (-900 1900) BN 31
J 2
(-888 1908);
DISPLAY 0.680851 (-888 1908);
PAINT GREEN (-888 1908);
FORCEPROP 2 LAST CDS_LIB standard
J 0
(-950 1900);
DISPLAY INVISIBLE (-950 1900);
FORCEPROP 1 LAST BODY_TYPE PLUMBING
J 2
(-950 1950);
DISPLAY 0.872340 (-950 1950);
PAINT GREEN (-950 1950);
DISPLAY INVISIBLE (-950 1950);
FORCEPROP 1 LAST HDL_TAP TRUE
J 2
(-1275 1775);
DISPLAY 0.872340 (-1275 1775);
DISPLAY INVISIBLE (-1275 1775);
FORCEPROP 1 LAST PATH I47
J 2
(-948 1900);
DISPLAY 0.872340 (-948 1900);
PAINT GREEN (-948 1900);
DISPLAY INVISIBLE (-948 1900);
FORCEADD TAP..1
R 2
(-950 1850);
FORCEPROP 3 LASTPIN (-900 1850) SIG_NAME M_B_CPU1_SB_DQ<30>
J 0
(-890 1860);
DISPLAY 0.659574 (-890 1860);
PAINT MONO (-890 1860);
DISPLAY INVISIBLE (-890 1860);
FORCEPROP 1 LASTPIN (-900 1850) BN 30
J 2
(-888 1858);
DISPLAY 0.680851 (-888 1858);
PAINT GREEN (-888 1858);
FORCEPROP 2 LAST CDS_LIB standard
J 0
(-950 1850);
DISPLAY INVISIBLE (-950 1850);
FORCEPROP 1 LAST BODY_TYPE PLUMBING
J 2
(-950 1900);
DISPLAY 0.872340 (-950 1900);
PAINT GREEN (-950 1900);
DISPLAY INVISIBLE (-950 1900);
FORCEPROP 1 LAST HDL_TAP TRUE
J 2
(-1275 1725);
DISPLAY 0.872340 (-1275 1725);
DISPLAY INVISIBLE (-1275 1725);
FORCEPROP 1 LAST PATH I48
J 2
(-948 1850);
DISPLAY 0.872340 (-948 1850);
PAINT GREEN (-948 1850);
DISPLAY INVISIBLE (-948 1850);
FORCEADD TAP..1
R 2
(-950 1950);
FORCEPROP 3 LASTPIN (-900 1950) SIG_NAME M_B_CPU1_SA_CB<0>
J 0
(-890 1960);
DISPLAY 0.659574 (-890 1960);
PAINT MONO (-890 1960);
DISPLAY INVISIBLE (-890 1960);
FORCEPROP 1 LASTPIN (-900 1950) BN 0
J 2
(-888 1958);
DISPLAY 0.680851 (-888 1958);
PAINT GREEN (-888 1958);
FORCEPROP 2 LAST CDS_LIB standard
J 0
(-950 1950);
DISPLAY INVISIBLE (-950 1950);
FORCEPROP 1 LAST BODY_TYPE PLUMBING
J 2
(-950 2000);
DISPLAY 0.872340 (-950 2000);
PAINT GREEN (-950 2000);
DISPLAY INVISIBLE (-950 2000);
FORCEPROP 1 LAST HDL_TAP TRUE
J 2
(-1275 1825);
DISPLAY 0.872340 (-1275 1825);
DISPLAY INVISIBLE (-1275 1825);
FORCEPROP 1 LAST PATH I49
J 2
(-948 1950);
DISPLAY 0.872340 (-948 1950);
PAINT GREEN (-948 1950);
DISPLAY INVISIBLE (-948 1950);
FORCEADD TAP..1
R 2
(-950 -150);
FORCEPROP 3 LASTPIN (-900 -150) SIG_NAME M_B_CPU1_CLK_DP<1>
J 0
(-890 -140);
DISPLAY 0.659574 (-890 -140);
PAINT MONO (-890 -140);
DISPLAY INVISIBLE (-890 -140);
FORCEPROP 1 LASTPIN (-900 -150) BN 1
J 2
(-888 -142);
DISPLAY 0.680851 (-888 -142);
PAINT GREEN (-888 -142);
FORCEPROP 2 LAST CDS_LIB standard
J 0
(-950 -150);
DISPLAY INVISIBLE (-950 -150);
FORCEPROP 1 LAST BODY_TYPE PLUMBING
J 2
(-950 -100);
DISPLAY 0.872340 (-950 -100);
PAINT GREEN (-950 -100);
DISPLAY INVISIBLE (-950 -100);
FORCEPROP 1 LAST HDL_TAP TRUE
J 2
(-1275 -275);
DISPLAY 0.872340 (-1275 -275);
DISPLAY INVISIBLE (-1275 -275);
FORCEPROP 1 LAST PATH I5
J 2
(-948 -150);
DISPLAY 0.872340 (-948 -150);
PAINT GREEN (-948 -150);
DISPLAY INVISIBLE (-948 -150);
FORCEADD OFFPAGE..3
R 2
(-1975 2325);
FORCEPROP 2 LAST $XR1 101 
J 0
(-2405 2325);
DISPLAY 0.638298 (-2405 2325);
PAINT MONO (-2405 2325);
FORCEPROP 2 LAST $XR0 100 
J 0
(-2285 2325);
DISPLAY 0.638298 (-2285 2325);
PAINT MONO (-2285 2325);
FORCEPROP 2 LAST CDS_LIB standard
J 0
(-1975 2325);
DISPLAY INVISIBLE (-1975 2325);
FORCEPROP 1 LAST OFFPAGE TRUE
J 2
(-2300 2200);
DISPLAY 0.872340 (-2300 2200);
DISPLAY INVISIBLE (-2300 2200);
FORCEPROP 1 LAST COMMENT_BODY TRUE
J 2
(-1925 2225);
DISPLAY 0.872340 (-1925 2225);
PAINT GREEN (-1925 2225);
DISPLAY INVISIBLE (-1925 2225);
FORCEPROP 2 LAST PATH I50
J 0
(-1925 2400);
DISPLAY 1.021277 (-1925 2400);
DISPLAY INVISIBLE (-1925 2400);
FORCEADD OFFPAGE..3
R 2
(-1975 3925);
FORCEPROP 2 LAST $XR1 101 
J 0
(-2405 3925);
DISPLAY 0.638298 (-2405 3925);
PAINT MONO (-2405 3925);
FORCEPROP 2 LAST $XR0 100 
J 0
(-2285 3925);
DISPLAY 0.638298 (-2285 3925);
PAINT MONO (-2285 3925);
FORCEPROP 2 LAST CDS_LIB standard
J 0
(-1975 3925);
DISPLAY INVISIBLE (-1975 3925);
FORCEPROP 1 LAST OFFPAGE TRUE
J 2
(-2300 3800);
DISPLAY 0.872340 (-2300 3800);
DISPLAY INVISIBLE (-2300 3800);
FORCEPROP 1 LAST COMMENT_BODY TRUE
J 2
(-1925 3825);
DISPLAY 0.872340 (-1925 3825);
PAINT GREEN (-1925 3825);
DISPLAY INVISIBLE (-1925 3825);
FORCEPROP 2 LAST PATH I51
J 0
(-1925 4000);
DISPLAY 1.021277 (-1925 4000);
DISPLAY INVISIBLE (-1925 4000);
FORCEADD TAP..1
R 2
(-950 2000);
FORCEPROP 3 LASTPIN (-900 2000) SIG_NAME M_B_CPU1_SA_CB<1>
J 0
(-890 2010);
DISPLAY 0.659574 (-890 2010);
PAINT MONO (-890 2010);
DISPLAY INVISIBLE (-890 2010);
FORCEPROP 1 LASTPIN (-900 2000) BN 1
J 2
(-888 2008);
DISPLAY 0.680851 (-888 2008);
PAINT GREEN (-888 2008);
FORCEPROP 2 LAST CDS_LIB standard
J 0
(-950 2000);
DISPLAY INVISIBLE (-950 2000);
FORCEPROP 1 LAST BODY_TYPE PLUMBING
J 2
(-950 2050);
DISPLAY 0.872340 (-950 2050);
PAINT GREEN (-950 2050);
DISPLAY INVISIBLE (-950 2050);
FORCEPROP 1 LAST HDL_TAP TRUE
J 2
(-1275 1875);
DISPLAY 0.872340 (-1275 1875);
DISPLAY INVISIBLE (-1275 1875);
FORCEPROP 1 LAST PATH I52
J 2
(-948 2000);
DISPLAY 0.872340 (-948 2000);
PAINT GREEN (-948 2000);
DISPLAY INVISIBLE (-948 2000);
FORCEADD TAP..1
R 2
(-950 2050);
FORCEPROP 3 LASTPIN (-900 2050) SIG_NAME M_B_CPU1_SA_CB<2>
J 0
(-890 2060);
DISPLAY 0.659574 (-890 2060);
PAINT MONO (-890 2060);
DISPLAY INVISIBLE (-890 2060);
FORCEPROP 1 LASTPIN (-900 2050) BN 2
J 2
(-888 2058);
DISPLAY 0.680851 (-888 2058);
PAINT GREEN (-888 2058);
FORCEPROP 2 LAST CDS_LIB standard
J 0
(-950 2050);
DISPLAY INVISIBLE (-950 2050);
FORCEPROP 1 LAST BODY_TYPE PLUMBING
J 2
(-950 2100);
DISPLAY 0.872340 (-950 2100);
PAINT GREEN (-950 2100);
DISPLAY INVISIBLE (-950 2100);
FORCEPROP 1 LAST HDL_TAP TRUE
J 2
(-1275 1925);
DISPLAY 0.872340 (-1275 1925);
DISPLAY INVISIBLE (-1275 1925);
FORCEPROP 1 LAST PATH I53
J 2
(-948 2050);
DISPLAY 0.872340 (-948 2050);
PAINT GREEN (-948 2050);
DISPLAY INVISIBLE (-948 2050);
FORCEADD TAP..1
R 2
(-950 2100);
FORCEPROP 3 LASTPIN (-900 2100) SIG_NAME M_B_CPU1_SA_CB<3>
J 0
(-890 2110);
DISPLAY 0.659574 (-890 2110);
PAINT MONO (-890 2110);
DISPLAY INVISIBLE (-890 2110);
FORCEPROP 1 LASTPIN (-900 2100) BN 3
J 2
(-888 2108);
DISPLAY 0.680851 (-888 2108);
PAINT GREEN (-888 2108);
FORCEPROP 2 LAST CDS_LIB standard
J 0
(-950 2100);
DISPLAY INVISIBLE (-950 2100);
FORCEPROP 1 LAST BODY_TYPE PLUMBING
J 2
(-950 2150);
DISPLAY 0.872340 (-950 2150);
PAINT GREEN (-950 2150);
DISPLAY INVISIBLE (-950 2150);
FORCEPROP 1 LAST HDL_TAP TRUE
J 2
(-1275 1975);
DISPLAY 0.872340 (-1275 1975);
DISPLAY INVISIBLE (-1275 1975);
FORCEPROP 1 LAST PATH I54
J 2
(-948 2100);
DISPLAY 0.872340 (-948 2100);
PAINT GREEN (-948 2100);
DISPLAY INVISIBLE (-948 2100);
FORCEADD TAP..1
R 2
(-950 2200);
FORCEPROP 3 LASTPIN (-900 2200) SIG_NAME M_B_CPU1_SA_CB<5>
J 0
(-890 2210);
DISPLAY 0.659574 (-890 2210);
PAINT MONO (-890 2210);
DISPLAY INVISIBLE (-890 2210);
FORCEPROP 1 LASTPIN (-900 2200) BN 5
J 2
(-888 2208);
DISPLAY 0.680851 (-888 2208);
PAINT GREEN (-888 2208);
FORCEPROP 2 LAST CDS_LIB standard
J 0
(-950 2200);
DISPLAY INVISIBLE (-950 2200);
FORCEPROP 1 LAST BODY_TYPE PLUMBING
J 2
(-950 2250);
DISPLAY 0.872340 (-950 2250);
PAINT GREEN (-950 2250);
DISPLAY INVISIBLE (-950 2250);
FORCEPROP 1 LAST HDL_TAP TRUE
J 2
(-1275 2075);
DISPLAY 0.872340 (-1275 2075);
DISPLAY INVISIBLE (-1275 2075);
FORCEPROP 1 LAST PATH I55
J 2
(-948 2200);
DISPLAY 0.872340 (-948 2200);
PAINT GREEN (-948 2200);
DISPLAY INVISIBLE (-948 2200);
FORCEADD TAP..1
R 2
(-950 2150);
FORCEPROP 3 LASTPIN (-900 2150) SIG_NAME M_B_CPU1_SA_CB<4>
J 0
(-890 2160);
DISPLAY 0.659574 (-890 2160);
PAINT MONO (-890 2160);
DISPLAY INVISIBLE (-890 2160);
FORCEPROP 1 LASTPIN (-900 2150) BN 4
J 2
(-888 2158);
DISPLAY 0.680851 (-888 2158);
PAINT GREEN (-888 2158);
FORCEPROP 2 LAST CDS_LIB standard
J 0
(-950 2150);
DISPLAY INVISIBLE (-950 2150);
FORCEPROP 1 LAST BODY_TYPE PLUMBING
J 2
(-950 2200);
DISPLAY 0.872340 (-950 2200);
PAINT GREEN (-950 2200);
DISPLAY INVISIBLE (-950 2200);
FORCEPROP 1 LAST HDL_TAP TRUE
J 2
(-1275 2025);
DISPLAY 0.872340 (-1275 2025);
DISPLAY INVISIBLE (-1275 2025);
FORCEPROP 1 LAST PATH I56
J 2
(-948 2150);
DISPLAY 0.872340 (-948 2150);
PAINT GREEN (-948 2150);
DISPLAY INVISIBLE (-948 2150);
FORCEADD TAP..1
R 2
(-950 2250);
FORCEPROP 3 LASTPIN (-900 2250) SIG_NAME M_B_CPU1_SA_CB<6>
J 0
(-890 2260);
DISPLAY 0.659574 (-890 2260);
PAINT MONO (-890 2260);
DISPLAY INVISIBLE (-890 2260);
FORCEPROP 1 LASTPIN (-900 2250) BN 6
J 2
(-888 2258);
DISPLAY 0.680851 (-888 2258);
PAINT GREEN (-888 2258);
FORCEPROP 2 LAST CDS_LIB standard
J 0
(-950 2250);
DISPLAY INVISIBLE (-950 2250);
FORCEPROP 1 LAST BODY_TYPE PLUMBING
J 2
(-950 2300);
DISPLAY 0.872340 (-950 2300);
PAINT GREEN (-950 2300);
DISPLAY INVISIBLE (-950 2300);
FORCEPROP 1 LAST HDL_TAP TRUE
J 2
(-1275 2125);
DISPLAY 0.872340 (-1275 2125);
DISPLAY INVISIBLE (-1275 2125);
FORCEPROP 1 LAST PATH I57
J 2
(-948 2250);
DISPLAY 0.872340 (-948 2250);
PAINT GREEN (-948 2250);
DISPLAY INVISIBLE (-948 2250);
FORCEADD TAP..1
R 2
(-950 2300);
FORCEPROP 3 LASTPIN (-900 2300) SIG_NAME M_B_CPU1_SA_CB<7>
J 0
(-890 2310);
DISPLAY 0.659574 (-890 2310);
PAINT MONO (-890 2310);
DISPLAY INVISIBLE (-890 2310);
FORCEPROP 1 LASTPIN (-900 2300) BN 7
J 2
(-888 2308);
DISPLAY 0.680851 (-888 2308);
PAINT GREEN (-888 2308);
FORCEPROP 2 LAST CDS_LIB standard
J 0
(-950 2300);
DISPLAY INVISIBLE (-950 2300);
FORCEPROP 1 LAST BODY_TYPE PLUMBING
J 2
(-950 2350);
DISPLAY 0.872340 (-950 2350);
PAINT GREEN (-950 2350);
DISPLAY INVISIBLE (-950 2350);
FORCEPROP 1 LAST HDL_TAP TRUE
J 2
(-1275 2175);
DISPLAY 0.872340 (-1275 2175);
DISPLAY INVISIBLE (-1275 2175);
FORCEPROP 1 LAST PATH I58
J 2
(-948 2300);
DISPLAY 0.872340 (-948 2300);
PAINT GREEN (-948 2300);
DISPLAY INVISIBLE (-948 2300);
FORCEADD TAP..1
R 2
(-950 2350);
FORCEPROP 3 LASTPIN (-900 2350) SIG_NAME M_B_CPU1_SA_DQ<0>
J 0
(-890 2360);
DISPLAY 0.659574 (-890 2360);
PAINT MONO (-890 2360);
DISPLAY INVISIBLE (-890 2360);
FORCEPROP 1 LASTPIN (-900 2350) BN 0
J 2
(-888 2358);
DISPLAY 0.680851 (-888 2358);
PAINT GREEN (-888 2358);
FORCEPROP 2 LAST CDS_LIB standard
J 0
(-950 2350);
DISPLAY INVISIBLE (-950 2350);
FORCEPROP 1 LAST BODY_TYPE PLUMBING
J 2
(-950 2400);
DISPLAY 0.872340 (-950 2400);
PAINT GREEN (-950 2400);
DISPLAY INVISIBLE (-950 2400);
FORCEPROP 1 LAST HDL_TAP TRUE
J 2
(-1275 2225);
DISPLAY 0.872340 (-1275 2225);
DISPLAY INVISIBLE (-1275 2225);
FORCEPROP 1 LAST PATH I59
J 2
(-948 2350);
DISPLAY 0.872340 (-948 2350);
PAINT GREEN (-948 2350);
DISPLAY INVISIBLE (-948 2350);
FORCEADD TAP..1
R 2
(-950 -200);
FORCEPROP 3 LASTPIN (-900 -200) SIG_NAME M_B_CPU1_CLK_DP<0>
J 0
(-890 -190);
DISPLAY 0.659574 (-890 -190);
PAINT MONO (-890 -190);
DISPLAY INVISIBLE (-890 -190);
FORCEPROP 1 LASTPIN (-900 -200) BN 0
J 2
(-888 -192);
DISPLAY 0.680851 (-888 -192);
PAINT GREEN (-888 -192);
FORCEPROP 2 LAST CDS_LIB standard
J 0
(-950 -200);
DISPLAY INVISIBLE (-950 -200);
FORCEPROP 1 LAST BODY_TYPE PLUMBING
J 2
(-950 -150);
DISPLAY 0.872340 (-950 -150);
PAINT GREEN (-950 -150);
DISPLAY INVISIBLE (-950 -150);
FORCEPROP 1 LAST HDL_TAP TRUE
J 2
(-1275 -325);
DISPLAY 0.872340 (-1275 -325);
DISPLAY INVISIBLE (-1275 -325);
FORCEPROP 1 LAST PATH I6
J 2
(-948 -200);
DISPLAY 0.872340 (-948 -200);
PAINT GREEN (-948 -200);
DISPLAY INVISIBLE (-948 -200);
FORCEADD TAP..1
R 2
(-950 2400);
FORCEPROP 3 LASTPIN (-900 2400) SIG_NAME M_B_CPU1_SA_DQ<1>
J 0
(-890 2410);
DISPLAY 0.659574 (-890 2410);
PAINT MONO (-890 2410);
DISPLAY INVISIBLE (-890 2410);
FORCEPROP 1 LASTPIN (-900 2400) BN 1
J 2
(-888 2408);
DISPLAY 0.680851 (-888 2408);
PAINT GREEN (-888 2408);
FORCEPROP 2 LAST CDS_LIB standard
J 0
(-950 2400);
DISPLAY INVISIBLE (-950 2400);
FORCEPROP 1 LAST BODY_TYPE PLUMBING
J 2
(-950 2450);
DISPLAY 0.872340 (-950 2450);
PAINT GREEN (-950 2450);
DISPLAY INVISIBLE (-950 2450);
FORCEPROP 1 LAST HDL_TAP TRUE
J 2
(-1275 2275);
DISPLAY 0.872340 (-1275 2275);
DISPLAY INVISIBLE (-1275 2275);
FORCEPROP 1 LAST PATH I60
J 2
(-948 2400);
DISPLAY 0.872340 (-948 2400);
PAINT GREEN (-948 2400);
DISPLAY INVISIBLE (-948 2400);
FORCEADD TAP..1
R 2
(-950 2450);
FORCEPROP 3 LASTPIN (-900 2450) SIG_NAME M_B_CPU1_SA_DQ<2>
J 0
(-890 2460);
DISPLAY 0.659574 (-890 2460);
PAINT MONO (-890 2460);
DISPLAY INVISIBLE (-890 2460);
FORCEPROP 1 LASTPIN (-900 2450) BN 2
J 2
(-888 2458);
DISPLAY 0.680851 (-888 2458);
PAINT GREEN (-888 2458);
FORCEPROP 2 LAST CDS_LIB standard
J 0
(-950 2450);
DISPLAY INVISIBLE (-950 2450);
FORCEPROP 1 LAST BODY_TYPE PLUMBING
J 2
(-950 2500);
DISPLAY 0.872340 (-950 2500);
PAINT GREEN (-950 2500);
DISPLAY INVISIBLE (-950 2500);
FORCEPROP 1 LAST HDL_TAP TRUE
J 2
(-1275 2325);
DISPLAY 0.872340 (-1275 2325);
DISPLAY INVISIBLE (-1275 2325);
FORCEPROP 1 LAST PATH I61
J 2
(-948 2450);
DISPLAY 0.872340 (-948 2450);
PAINT GREEN (-948 2450);
DISPLAY INVISIBLE (-948 2450);
FORCEADD TAP..1
R 2
(-950 2500);
FORCEPROP 3 LASTPIN (-900 2500) SIG_NAME M_B_CPU1_SA_DQ<3>
J 0
(-890 2510);
DISPLAY 0.659574 (-890 2510);
PAINT MONO (-890 2510);
DISPLAY INVISIBLE (-890 2510);
FORCEPROP 1 LASTPIN (-900 2500) BN 3
J 2
(-888 2508);
DISPLAY 0.680851 (-888 2508);
PAINT GREEN (-888 2508);
FORCEPROP 2 LAST CDS_LIB standard
J 0
(-950 2500);
DISPLAY INVISIBLE (-950 2500);
FORCEPROP 1 LAST BODY_TYPE PLUMBING
J 2
(-950 2550);
DISPLAY 0.872340 (-950 2550);
PAINT GREEN (-950 2550);
DISPLAY INVISIBLE (-950 2550);
FORCEPROP 1 LAST HDL_TAP TRUE
J 2
(-1275 2375);
DISPLAY 0.872340 (-1275 2375);
DISPLAY INVISIBLE (-1275 2375);
FORCEPROP 1 LAST PATH I62
J 2
(-948 2500);
DISPLAY 0.872340 (-948 2500);
PAINT GREEN (-948 2500);
DISPLAY INVISIBLE (-948 2500);
FORCEADD TAP..1
R 2
(-950 2550);
FORCEPROP 3 LASTPIN (-900 2550) SIG_NAME M_B_CPU1_SA_DQ<4>
J 0
(-890 2560);
DISPLAY 0.659574 (-890 2560);
PAINT MONO (-890 2560);
DISPLAY INVISIBLE (-890 2560);
FORCEPROP 1 LASTPIN (-900 2550) BN 4
J 2
(-888 2558);
DISPLAY 0.680851 (-888 2558);
PAINT GREEN (-888 2558);
FORCEPROP 2 LAST CDS_LIB standard
J 0
(-950 2550);
DISPLAY INVISIBLE (-950 2550);
FORCEPROP 1 LAST BODY_TYPE PLUMBING
J 2
(-950 2600);
DISPLAY 0.872340 (-950 2600);
PAINT GREEN (-950 2600);
DISPLAY INVISIBLE (-950 2600);
FORCEPROP 1 LAST HDL_TAP TRUE
J 2
(-1275 2425);
DISPLAY 0.872340 (-1275 2425);
DISPLAY INVISIBLE (-1275 2425);
FORCEPROP 1 LAST PATH I63
J 2
(-948 2550);
DISPLAY 0.872340 (-948 2550);
PAINT GREEN (-948 2550);
DISPLAY INVISIBLE (-948 2550);
FORCEADD TAP..1
R 2
(-950 2600);
FORCEPROP 3 LASTPIN (-900 2600) SIG_NAME M_B_CPU1_SA_DQ<5>
J 0
(-890 2610);
DISPLAY 0.659574 (-890 2610);
PAINT MONO (-890 2610);
DISPLAY INVISIBLE (-890 2610);
FORCEPROP 1 LASTPIN (-900 2600) BN 5
J 2
(-888 2608);
DISPLAY 0.680851 (-888 2608);
PAINT GREEN (-888 2608);
FORCEPROP 2 LAST CDS_LIB standard
J 0
(-950 2600);
DISPLAY INVISIBLE (-950 2600);
FORCEPROP 1 LAST BODY_TYPE PLUMBING
J 2
(-950 2650);
DISPLAY 0.872340 (-950 2650);
PAINT GREEN (-950 2650);
DISPLAY INVISIBLE (-950 2650);
FORCEPROP 1 LAST HDL_TAP TRUE
J 2
(-1275 2475);
DISPLAY 0.872340 (-1275 2475);
DISPLAY INVISIBLE (-1275 2475);
FORCEPROP 1 LAST PATH I64
J 2
(-948 2600);
DISPLAY 0.872340 (-948 2600);
PAINT GREEN (-948 2600);
DISPLAY INVISIBLE (-948 2600);
FORCEADD TAP..1
R 2
(-950 2700);
FORCEPROP 3 LASTPIN (-900 2700) SIG_NAME M_B_CPU1_SA_DQ<7>
J 0
(-890 2710);
DISPLAY 0.659574 (-890 2710);
PAINT MONO (-890 2710);
DISPLAY INVISIBLE (-890 2710);
FORCEPROP 1 LASTPIN (-900 2700) BN 7
J 2
(-888 2708);
DISPLAY 0.680851 (-888 2708);
PAINT GREEN (-888 2708);
FORCEPROP 2 LAST CDS_LIB standard
J 0
(-950 2700);
DISPLAY INVISIBLE (-950 2700);
FORCEPROP 1 LAST BODY_TYPE PLUMBING
J 2
(-950 2750);
DISPLAY 0.872340 (-950 2750);
PAINT GREEN (-950 2750);
DISPLAY INVISIBLE (-950 2750);
FORCEPROP 1 LAST HDL_TAP TRUE
J 2
(-1275 2575);
DISPLAY 0.872340 (-1275 2575);
DISPLAY INVISIBLE (-1275 2575);
FORCEPROP 1 LAST PATH I65
J 2
(-948 2700);
DISPLAY 0.872340 (-948 2700);
PAINT GREEN (-948 2700);
DISPLAY INVISIBLE (-948 2700);
FORCEADD TAP..1
R 2
(-950 2650);
FORCEPROP 3 LASTPIN (-900 2650) SIG_NAME M_B_CPU1_SA_DQ<6>
J 0
(-890 2660);
DISPLAY 0.659574 (-890 2660);
PAINT MONO (-890 2660);
DISPLAY INVISIBLE (-890 2660);
FORCEPROP 1 LASTPIN (-900 2650) BN 6
J 2
(-888 2658);
DISPLAY 0.680851 (-888 2658);
PAINT GREEN (-888 2658);
FORCEPROP 2 LAST CDS_LIB standard
J 0
(-950 2650);
DISPLAY INVISIBLE (-950 2650);
FORCEPROP 1 LAST BODY_TYPE PLUMBING
J 2
(-950 2700);
DISPLAY 0.872340 (-950 2700);
PAINT GREEN (-950 2700);
DISPLAY INVISIBLE (-950 2700);
FORCEPROP 1 LAST HDL_TAP TRUE
J 2
(-1275 2525);
DISPLAY 0.872340 (-1275 2525);
DISPLAY INVISIBLE (-1275 2525);
FORCEPROP 1 LAST PATH I66
J 2
(-948 2650);
DISPLAY 0.872340 (-948 2650);
PAINT GREEN (-948 2650);
DISPLAY INVISIBLE (-948 2650);
FORCEADD TAP..1
R 2
(-950 2750);
FORCEPROP 3 LASTPIN (-900 2750) SIG_NAME M_B_CPU1_SA_DQ<8>
J 0
(-890 2760);
DISPLAY 0.659574 (-890 2760);
PAINT MONO (-890 2760);
DISPLAY INVISIBLE (-890 2760);
FORCEPROP 1 LASTPIN (-900 2750) BN 8
J 2
(-888 2758);
DISPLAY 0.680851 (-888 2758);
PAINT GREEN (-888 2758);
FORCEPROP 2 LAST CDS_LIB standard
J 0
(-950 2750);
DISPLAY INVISIBLE (-950 2750);
FORCEPROP 1 LAST BODY_TYPE PLUMBING
J 2
(-950 2800);
DISPLAY 0.872340 (-950 2800);
PAINT GREEN (-950 2800);
DISPLAY INVISIBLE (-950 2800);
FORCEPROP 1 LAST HDL_TAP TRUE
J 2
(-1275 2625);
DISPLAY 0.872340 (-1275 2625);
DISPLAY INVISIBLE (-1275 2625);
FORCEPROP 1 LAST PATH I67
J 2
(-948 2750);
DISPLAY 0.872340 (-948 2750);
PAINT GREEN (-948 2750);
DISPLAY INVISIBLE (-948 2750);
FORCEADD TAP..1
R 2
(-950 2800);
FORCEPROP 3 LASTPIN (-900 2800) SIG_NAME M_B_CPU1_SA_DQ<9>
J 0
(-890 2810);
DISPLAY 0.659574 (-890 2810);
PAINT MONO (-890 2810);
DISPLAY INVISIBLE (-890 2810);
FORCEPROP 1 LASTPIN (-900 2800) BN 9
J 2
(-888 2808);
DISPLAY 0.680851 (-888 2808);
PAINT GREEN (-888 2808);
FORCEPROP 2 LAST CDS_LIB standard
J 0
(-950 2800);
DISPLAY INVISIBLE (-950 2800);
FORCEPROP 1 LAST BODY_TYPE PLUMBING
J 2
(-950 2850);
DISPLAY 0.872340 (-950 2850);
PAINT GREEN (-950 2850);
DISPLAY INVISIBLE (-950 2850);
FORCEPROP 1 LAST HDL_TAP TRUE
J 2
(-1275 2675);
DISPLAY 0.872340 (-1275 2675);
DISPLAY INVISIBLE (-1275 2675);
FORCEPROP 1 LAST PATH I68
J 2
(-948 2800);
DISPLAY 0.872340 (-948 2800);
PAINT GREEN (-948 2800);
DISPLAY INVISIBLE (-948 2800);
FORCEADD TAP..1
R 2
(-950 2850);
FORCEPROP 3 LASTPIN (-900 2850) SIG_NAME M_B_CPU1_SA_DQ<10>
J 0
(-890 2860);
DISPLAY 0.659574 (-890 2860);
PAINT MONO (-890 2860);
DISPLAY INVISIBLE (-890 2860);
FORCEPROP 1 LASTPIN (-900 2850) BN 10
J 2
(-888 2858);
DISPLAY 0.680851 (-888 2858);
PAINT GREEN (-888 2858);
FORCEPROP 2 LAST CDS_LIB standard
J 0
(-950 2850);
DISPLAY INVISIBLE (-950 2850);
FORCEPROP 1 LAST BODY_TYPE PLUMBING
J 2
(-950 2900);
DISPLAY 0.872340 (-950 2900);
PAINT GREEN (-950 2900);
DISPLAY INVISIBLE (-950 2900);
FORCEPROP 1 LAST HDL_TAP TRUE
J 2
(-1275 2725);
DISPLAY 0.872340 (-1275 2725);
DISPLAY INVISIBLE (-1275 2725);
FORCEPROP 1 LAST PATH I69
J 2
(-948 2850);
DISPLAY 0.872340 (-948 2850);
PAINT GREEN (-948 2850);
DISPLAY INVISIBLE (-948 2850);
FORCEADD OFFPAGE..3
R 2
(-1975 325);
FORCEPROP 2 LAST $XR1 101 
J 0
(-2405 325);
DISPLAY 0.638298 (-2405 325);
PAINT MONO (-2405 325);
FORCEPROP 2 LAST $XR0 100 
J 0
(-2285 325);
DISPLAY 0.638298 (-2285 325);
PAINT MONO (-2285 325);
FORCEPROP 2 LAST CDS_LIB standard
J 0
(-1975 325);
DISPLAY INVISIBLE (-1975 325);
FORCEPROP 1 LAST OFFPAGE TRUE
J 2
(-2300 200);
DISPLAY 0.872340 (-2300 200);
DISPLAY INVISIBLE (-2300 200);
FORCEPROP 1 LAST COMMENT_BODY TRUE
J 2
(-1925 225);
DISPLAY 0.872340 (-1925 225);
PAINT GREEN (-1925 225);
DISPLAY INVISIBLE (-1925 225);
FORCEPROP 2 LAST PATH I7
J 0
(-1925 400);
DISPLAY 1.021277 (-1925 400);
DISPLAY INVISIBLE (-1925 400);
FORCEADD TAP..1
R 2
(-950 2900);
FORCEPROP 3 LASTPIN (-900 2900) SIG_NAME M_B_CPU1_SA_DQ<11>
J 0
(-890 2910);
DISPLAY 0.659574 (-890 2910);
PAINT MONO (-890 2910);
DISPLAY INVISIBLE (-890 2910);
FORCEPROP 1 LASTPIN (-900 2900) BN 11
J 2
(-888 2908);
DISPLAY 0.680851 (-888 2908);
PAINT GREEN (-888 2908);
FORCEPROP 2 LAST CDS_LIB standard
J 0
(-950 2900);
DISPLAY INVISIBLE (-950 2900);
FORCEPROP 1 LAST BODY_TYPE PLUMBING
J 2
(-950 2950);
DISPLAY 0.872340 (-950 2950);
PAINT GREEN (-950 2950);
DISPLAY INVISIBLE (-950 2950);
FORCEPROP 1 LAST HDL_TAP TRUE
J 2
(-1275 2775);
DISPLAY 0.872340 (-1275 2775);
DISPLAY INVISIBLE (-1275 2775);
FORCEPROP 1 LAST PATH I70
J 2
(-948 2900);
DISPLAY 0.872340 (-948 2900);
PAINT GREEN (-948 2900);
DISPLAY INVISIBLE (-948 2900);
FORCEADD TAP..1
R 2
(-950 2950);
FORCEPROP 3 LASTPIN (-900 2950) SIG_NAME M_B_CPU1_SA_DQ<12>
J 0
(-890 2960);
DISPLAY 0.659574 (-890 2960);
PAINT MONO (-890 2960);
DISPLAY INVISIBLE (-890 2960);
FORCEPROP 1 LASTPIN (-900 2950) BN 12
J 2
(-888 2958);
DISPLAY 0.680851 (-888 2958);
PAINT GREEN (-888 2958);
FORCEPROP 2 LAST CDS_LIB standard
J 0
(-950 2950);
DISPLAY INVISIBLE (-950 2950);
FORCEPROP 1 LAST BODY_TYPE PLUMBING
J 2
(-950 3000);
DISPLAY 0.872340 (-950 3000);
PAINT GREEN (-950 3000);
DISPLAY INVISIBLE (-950 3000);
FORCEPROP 1 LAST HDL_TAP TRUE
J 2
(-1275 2825);
DISPLAY 0.872340 (-1275 2825);
DISPLAY INVISIBLE (-1275 2825);
FORCEPROP 1 LAST PATH I71
J 2
(-948 2950);
DISPLAY 0.872340 (-948 2950);
PAINT GREEN (-948 2950);
DISPLAY INVISIBLE (-948 2950);
FORCEADD TAP..1
R 2
(-950 3000);
FORCEPROP 3 LASTPIN (-900 3000) SIG_NAME M_B_CPU1_SA_DQ<13>
J 0
(-890 3010);
DISPLAY 0.659574 (-890 3010);
PAINT MONO (-890 3010);
DISPLAY INVISIBLE (-890 3010);
FORCEPROP 1 LASTPIN (-900 3000) BN 13
J 2
(-888 3008);
DISPLAY 0.680851 (-888 3008);
PAINT GREEN (-888 3008);
FORCEPROP 2 LAST CDS_LIB standard
J 0
(-950 3000);
DISPLAY INVISIBLE (-950 3000);
FORCEPROP 1 LAST BODY_TYPE PLUMBING
J 2
(-950 3050);
DISPLAY 0.872340 (-950 3050);
PAINT GREEN (-950 3050);
DISPLAY INVISIBLE (-950 3050);
FORCEPROP 1 LAST HDL_TAP TRUE
J 2
(-1275 2875);
DISPLAY 0.872340 (-1275 2875);
DISPLAY INVISIBLE (-1275 2875);
FORCEPROP 1 LAST PATH I72
J 2
(-948 3000);
DISPLAY 0.872340 (-948 3000);
PAINT GREEN (-948 3000);
DISPLAY INVISIBLE (-948 3000);
FORCEADD TAP..1
R 2
(-950 3050);
FORCEPROP 3 LASTPIN (-900 3050) SIG_NAME M_B_CPU1_SA_DQ<14>
J 0
(-890 3060);
DISPLAY 0.659574 (-890 3060);
PAINT MONO (-890 3060);
DISPLAY INVISIBLE (-890 3060);
FORCEPROP 1 LASTPIN (-900 3050) BN 14
J 2
(-888 3058);
DISPLAY 0.680851 (-888 3058);
PAINT GREEN (-888 3058);
FORCEPROP 2 LAST CDS_LIB standard
J 0
(-950 3050);
DISPLAY INVISIBLE (-950 3050);
FORCEPROP 1 LAST BODY_TYPE PLUMBING
J 2
(-950 3100);
DISPLAY 0.872340 (-950 3100);
PAINT GREEN (-950 3100);
DISPLAY INVISIBLE (-950 3100);
FORCEPROP 1 LAST HDL_TAP TRUE
J 2
(-1275 2925);
DISPLAY 0.872340 (-1275 2925);
DISPLAY INVISIBLE (-1275 2925);
FORCEPROP 1 LAST PATH I73
J 2
(-948 3050);
DISPLAY 0.872340 (-948 3050);
PAINT GREEN (-948 3050);
DISPLAY INVISIBLE (-948 3050);
FORCEADD TAP..1
R 2
(-950 3100);
FORCEPROP 3 LASTPIN (-900 3100) SIG_NAME M_B_CPU1_SA_DQ<15>
J 0
(-890 3110);
DISPLAY 0.659574 (-890 3110);
PAINT MONO (-890 3110);
DISPLAY INVISIBLE (-890 3110);
FORCEPROP 1 LASTPIN (-900 3100) BN 15
J 2
(-888 3108);
DISPLAY 0.680851 (-888 3108);
PAINT GREEN (-888 3108);
FORCEPROP 2 LAST CDS_LIB standard
J 0
(-950 3100);
DISPLAY INVISIBLE (-950 3100);
FORCEPROP 1 LAST BODY_TYPE PLUMBING
J 2
(-950 3150);
DISPLAY 0.872340 (-950 3150);
PAINT GREEN (-950 3150);
DISPLAY INVISIBLE (-950 3150);
FORCEPROP 1 LAST HDL_TAP TRUE
J 2
(-1275 2975);
DISPLAY 0.872340 (-1275 2975);
DISPLAY INVISIBLE (-1275 2975);
FORCEPROP 1 LAST PATH I74
J 2
(-948 3100);
DISPLAY 0.872340 (-948 3100);
PAINT GREEN (-948 3100);
DISPLAY INVISIBLE (-948 3100);
FORCEADD TAP..1
R 2
(-950 3200);
FORCEPROP 3 LASTPIN (-900 3200) SIG_NAME M_B_CPU1_SA_DQ<17>
J 0
(-890 3210);
DISPLAY 0.659574 (-890 3210);
PAINT MONO (-890 3210);
DISPLAY INVISIBLE (-890 3210);
FORCEPROP 1 LASTPIN (-900 3200) BN 17
J 2
(-888 3208);
DISPLAY 0.680851 (-888 3208);
PAINT GREEN (-888 3208);
FORCEPROP 2 LAST CDS_LIB standard
J 0
(-950 3200);
DISPLAY INVISIBLE (-950 3200);
FORCEPROP 1 LAST BODY_TYPE PLUMBING
J 2
(-950 3250);
DISPLAY 0.872340 (-950 3250);
PAINT GREEN (-950 3250);
DISPLAY INVISIBLE (-950 3250);
FORCEPROP 1 LAST HDL_TAP TRUE
J 2
(-1275 3075);
DISPLAY 0.872340 (-1275 3075);
DISPLAY INVISIBLE (-1275 3075);
FORCEPROP 1 LAST PATH I75
J 2
(-948 3200);
DISPLAY 0.872340 (-948 3200);
PAINT GREEN (-948 3200);
DISPLAY INVISIBLE (-948 3200);
FORCEADD TAP..1
R 2
(-950 3150);
FORCEPROP 3 LASTPIN (-900 3150) SIG_NAME M_B_CPU1_SA_DQ<16>
J 0
(-890 3160);
DISPLAY 0.659574 (-890 3160);
PAINT MONO (-890 3160);
DISPLAY INVISIBLE (-890 3160);
FORCEPROP 1 LASTPIN (-900 3150) BN 16
J 2
(-888 3158);
DISPLAY 0.680851 (-888 3158);
PAINT GREEN (-888 3158);
FORCEPROP 2 LAST CDS_LIB standard
J 0
(-950 3150);
DISPLAY INVISIBLE (-950 3150);
FORCEPROP 1 LAST BODY_TYPE PLUMBING
J 2
(-950 3200);
DISPLAY 0.872340 (-950 3200);
PAINT GREEN (-950 3200);
DISPLAY INVISIBLE (-950 3200);
FORCEPROP 1 LAST HDL_TAP TRUE
J 2
(-1275 3025);
DISPLAY 0.872340 (-1275 3025);
DISPLAY INVISIBLE (-1275 3025);
FORCEPROP 1 LAST PATH I76
J 2
(-948 3150);
DISPLAY 0.872340 (-948 3150);
PAINT GREEN (-948 3150);
DISPLAY INVISIBLE (-948 3150);
FORCEADD TAP..1
R 2
(-950 3250);
FORCEPROP 3 LASTPIN (-900 3250) SIG_NAME M_B_CPU1_SA_DQ<18>
J 0
(-890 3260);
DISPLAY 0.659574 (-890 3260);
PAINT MONO (-890 3260);
DISPLAY INVISIBLE (-890 3260);
FORCEPROP 1 LASTPIN (-900 3250) BN 18
J 2
(-888 3258);
DISPLAY 0.680851 (-888 3258);
PAINT GREEN (-888 3258);
FORCEPROP 2 LAST CDS_LIB standard
J 0
(-950 3250);
DISPLAY INVISIBLE (-950 3250);
FORCEPROP 1 LAST BODY_TYPE PLUMBING
J 2
(-950 3300);
DISPLAY 0.872340 (-950 3300);
PAINT GREEN (-950 3300);
DISPLAY INVISIBLE (-950 3300);
FORCEPROP 1 LAST HDL_TAP TRUE
J 2
(-1275 3125);
DISPLAY 0.872340 (-1275 3125);
DISPLAY INVISIBLE (-1275 3125);
FORCEPROP 1 LAST PATH I77
J 2
(-948 3250);
DISPLAY 0.872340 (-948 3250);
PAINT GREEN (-948 3250);
DISPLAY INVISIBLE (-948 3250);
FORCEADD TAP..1
R 2
(-950 3350);
FORCEPROP 3 LASTPIN (-900 3350) SIG_NAME M_B_CPU1_SA_DQ<20>
J 0
(-890 3360);
DISPLAY 0.659574 (-890 3360);
PAINT MONO (-890 3360);
DISPLAY INVISIBLE (-890 3360);
FORCEPROP 1 LASTPIN (-900 3350) BN 20
J 2
(-888 3358);
DISPLAY 0.680851 (-888 3358);
PAINT GREEN (-888 3358);
FORCEPROP 2 LAST CDS_LIB standard
J 0
(-950 3350);
DISPLAY INVISIBLE (-950 3350);
FORCEPROP 1 LAST BODY_TYPE PLUMBING
J 2
(-950 3400);
DISPLAY 0.872340 (-950 3400);
PAINT GREEN (-950 3400);
DISPLAY INVISIBLE (-950 3400);
FORCEPROP 1 LAST HDL_TAP TRUE
J 2
(-1275 3225);
DISPLAY 0.872340 (-1275 3225);
DISPLAY INVISIBLE (-1275 3225);
FORCEPROP 1 LAST PATH I78
J 2
(-948 3350);
DISPLAY 0.872340 (-948 3350);
PAINT GREEN (-948 3350);
DISPLAY INVISIBLE (-948 3350);
FORCEADD TAP..1
R 2
(-950 3300);
FORCEPROP 3 LASTPIN (-900 3300) SIG_NAME M_B_CPU1_SA_DQ<19>
J 0
(-890 3310);
DISPLAY 0.659574 (-890 3310);
PAINT MONO (-890 3310);
DISPLAY INVISIBLE (-890 3310);
FORCEPROP 1 LASTPIN (-900 3300) BN 19
J 2
(-888 3308);
DISPLAY 0.680851 (-888 3308);
PAINT GREEN (-888 3308);
FORCEPROP 2 LAST CDS_LIB standard
J 0
(-950 3300);
DISPLAY INVISIBLE (-950 3300);
FORCEPROP 1 LAST BODY_TYPE PLUMBING
J 2
(-950 3350);
DISPLAY 0.872340 (-950 3350);
PAINT GREEN (-950 3350);
DISPLAY INVISIBLE (-950 3350);
FORCEPROP 1 LAST HDL_TAP TRUE
J 2
(-1275 3175);
DISPLAY 0.872340 (-1275 3175);
DISPLAY INVISIBLE (-1275 3175);
FORCEPROP 1 LAST PATH I79
J 2
(-948 3300);
DISPLAY 0.872340 (-948 3300);
PAINT GREEN (-948 3300);
DISPLAY INVISIBLE (-948 3300);
FORCEADD OFFPAGE..3
R 2
(-1975 1925);
FORCEPROP 2 LAST $XR1 101 
J 0
(-2405 1925);
DISPLAY 0.638298 (-2405 1925);
PAINT MONO (-2405 1925);
FORCEPROP 2 LAST $XR0 100 
J 0
(-2285 1925);
DISPLAY 0.638298 (-2285 1925);
PAINT MONO (-2285 1925);
FORCEPROP 2 LAST CDS_LIB standard
J 0
(-1975 1925);
DISPLAY INVISIBLE (-1975 1925);
FORCEPROP 1 LAST OFFPAGE TRUE
J 2
(-2300 1800);
DISPLAY 0.872340 (-2300 1800);
DISPLAY INVISIBLE (-2300 1800);
FORCEPROP 1 LAST COMMENT_BODY TRUE
J 2
(-1925 1825);
DISPLAY 0.872340 (-1925 1825);
PAINT GREEN (-1925 1825);
DISPLAY INVISIBLE (-1925 1825);
FORCEPROP 2 LAST PATH I8
J 0
(-1925 2000);
DISPLAY 1.021277 (-1925 2000);
DISPLAY INVISIBLE (-1925 2000);
FORCEADD TAP..1
R 2
(-950 3450);
FORCEPROP 3 LASTPIN (-900 3450) SIG_NAME M_B_CPU1_SA_DQ<22>
J 0
(-890 3460);
DISPLAY 0.659574 (-890 3460);
PAINT MONO (-890 3460);
DISPLAY INVISIBLE (-890 3460);
FORCEPROP 1 LASTPIN (-900 3450) BN 22
J 2
(-888 3458);
DISPLAY 0.680851 (-888 3458);
PAINT GREEN (-888 3458);
FORCEPROP 2 LAST CDS_LIB standard
J 0
(-950 3450);
DISPLAY INVISIBLE (-950 3450);
FORCEPROP 1 LAST BODY_TYPE PLUMBING
J 2
(-950 3500);
DISPLAY 0.872340 (-950 3500);
PAINT GREEN (-950 3500);
DISPLAY INVISIBLE (-950 3500);
FORCEPROP 1 LAST HDL_TAP TRUE
J 2
(-1275 3325);
DISPLAY 0.872340 (-1275 3325);
DISPLAY INVISIBLE (-1275 3325);
FORCEPROP 1 LAST PATH I80
J 2
(-948 3450);
DISPLAY 0.872340 (-948 3450);
PAINT GREEN (-948 3450);
DISPLAY INVISIBLE (-948 3450);
FORCEADD TAP..1
R 2
(-950 3400);
FORCEPROP 3 LASTPIN (-900 3400) SIG_NAME M_B_CPU1_SA_DQ<21>
J 0
(-890 3410);
DISPLAY 0.659574 (-890 3410);
PAINT MONO (-890 3410);
DISPLAY INVISIBLE (-890 3410);
FORCEPROP 1 LASTPIN (-900 3400) BN 21
J 2
(-888 3408);
DISPLAY 0.680851 (-888 3408);
PAINT GREEN (-888 3408);
FORCEPROP 2 LAST CDS_LIB standard
J 0
(-950 3400);
DISPLAY INVISIBLE (-950 3400);
FORCEPROP 1 LAST BODY_TYPE PLUMBING
J 2
(-950 3450);
DISPLAY 0.872340 (-950 3450);
PAINT GREEN (-950 3450);
DISPLAY INVISIBLE (-950 3450);
FORCEPROP 1 LAST HDL_TAP TRUE
J 2
(-1275 3275);
DISPLAY 0.872340 (-1275 3275);
DISPLAY INVISIBLE (-1275 3275);
FORCEPROP 1 LAST PATH I81
J 2
(-948 3400);
DISPLAY 0.872340 (-948 3400);
PAINT GREEN (-948 3400);
DISPLAY INVISIBLE (-948 3400);
FORCEADD TAP..1
R 2
(-950 3500);
FORCEPROP 3 LASTPIN (-900 3500) SIG_NAME M_B_CPU1_SA_DQ<23>
J 0
(-890 3510);
DISPLAY 0.659574 (-890 3510);
PAINT MONO (-890 3510);
DISPLAY INVISIBLE (-890 3510);
FORCEPROP 1 LASTPIN (-900 3500) BN 23
J 2
(-888 3508);
DISPLAY 0.680851 (-888 3508);
PAINT GREEN (-888 3508);
FORCEPROP 2 LAST CDS_LIB standard
J 0
(-950 3500);
DISPLAY INVISIBLE (-950 3500);
FORCEPROP 1 LAST BODY_TYPE PLUMBING
J 2
(-950 3550);
DISPLAY 0.872340 (-950 3550);
PAINT GREEN (-950 3550);
DISPLAY INVISIBLE (-950 3550);
FORCEPROP 1 LAST HDL_TAP TRUE
J 2
(-1275 3375);
DISPLAY 0.872340 (-1275 3375);
DISPLAY INVISIBLE (-1275 3375);
FORCEPROP 1 LAST PATH I82
J 2
(-948 3500);
DISPLAY 0.872340 (-948 3500);
PAINT GREEN (-948 3500);
DISPLAY INVISIBLE (-948 3500);
FORCEADD TAP..1
R 2
(-950 3600);
FORCEPROP 3 LASTPIN (-900 3600) SIG_NAME M_B_CPU1_SA_DQ<25>
J 0
(-890 3610);
DISPLAY 0.659574 (-890 3610);
PAINT MONO (-890 3610);
DISPLAY INVISIBLE (-890 3610);
FORCEPROP 1 LASTPIN (-900 3600) BN 25
J 2
(-888 3608);
DISPLAY 0.680851 (-888 3608);
PAINT GREEN (-888 3608);
FORCEPROP 2 LAST CDS_LIB standard
J 0
(-950 3600);
DISPLAY INVISIBLE (-950 3600);
FORCEPROP 1 LAST BODY_TYPE PLUMBING
J 2
(-950 3650);
DISPLAY 0.872340 (-950 3650);
PAINT GREEN (-950 3650);
DISPLAY INVISIBLE (-950 3650);
FORCEPROP 1 LAST HDL_TAP TRUE
J 2
(-1275 3475);
DISPLAY 0.872340 (-1275 3475);
DISPLAY INVISIBLE (-1275 3475);
FORCEPROP 1 LAST PATH I83
J 2
(-948 3600);
DISPLAY 0.872340 (-948 3600);
PAINT GREEN (-948 3600);
DISPLAY INVISIBLE (-948 3600);
FORCEADD TAP..1
R 2
(-950 3550);
FORCEPROP 3 LASTPIN (-900 3550) SIG_NAME M_B_CPU1_SA_DQ<24>
J 0
(-890 3560);
DISPLAY 0.659574 (-890 3560);
PAINT MONO (-890 3560);
DISPLAY INVISIBLE (-890 3560);
FORCEPROP 1 LASTPIN (-900 3550) BN 24
J 2
(-888 3558);
DISPLAY 0.680851 (-888 3558);
PAINT GREEN (-888 3558);
FORCEPROP 2 LAST CDS_LIB standard
J 0
(-950 3550);
DISPLAY INVISIBLE (-950 3550);
FORCEPROP 1 LAST BODY_TYPE PLUMBING
J 2
(-950 3600);
DISPLAY 0.872340 (-950 3600);
PAINT GREEN (-950 3600);
DISPLAY INVISIBLE (-950 3600);
FORCEPROP 1 LAST HDL_TAP TRUE
J 2
(-1275 3425);
DISPLAY 0.872340 (-1275 3425);
DISPLAY INVISIBLE (-1275 3425);
FORCEPROP 1 LAST PATH I84
J 2
(-948 3550);
DISPLAY 0.872340 (-948 3550);
PAINT GREEN (-948 3550);
DISPLAY INVISIBLE (-948 3550);
FORCEADD TAP..1
R 2
(-950 3700);
FORCEPROP 3 LASTPIN (-900 3700) SIG_NAME M_B_CPU1_SA_DQ<27>
J 0
(-890 3710);
DISPLAY 0.659574 (-890 3710);
PAINT MONO (-890 3710);
DISPLAY INVISIBLE (-890 3710);
FORCEPROP 1 LASTPIN (-900 3700) BN 27
J 2
(-888 3708);
DISPLAY 0.680851 (-888 3708);
PAINT GREEN (-888 3708);
FORCEPROP 2 LAST CDS_LIB standard
J 0
(-950 3700);
DISPLAY INVISIBLE (-950 3700);
FORCEPROP 1 LAST BODY_TYPE PLUMBING
J 2
(-950 3750);
DISPLAY 0.872340 (-950 3750);
PAINT GREEN (-950 3750);
DISPLAY INVISIBLE (-950 3750);
FORCEPROP 1 LAST HDL_TAP TRUE
J 2
(-1275 3575);
DISPLAY 0.872340 (-1275 3575);
DISPLAY INVISIBLE (-1275 3575);
FORCEPROP 1 LAST PATH I85
J 2
(-948 3700);
DISPLAY 0.872340 (-948 3700);
PAINT GREEN (-948 3700);
DISPLAY INVISIBLE (-948 3700);
FORCEADD TAP..1
R 2
(-950 3650);
FORCEPROP 3 LASTPIN (-900 3650) SIG_NAME M_B_CPU1_SA_DQ<26>
J 0
(-890 3660);
DISPLAY 0.659574 (-890 3660);
PAINT MONO (-890 3660);
DISPLAY INVISIBLE (-890 3660);
FORCEPROP 1 LASTPIN (-900 3650) BN 26
J 2
(-888 3658);
DISPLAY 0.680851 (-888 3658);
PAINT GREEN (-888 3658);
FORCEPROP 2 LAST CDS_LIB standard
J 0
(-950 3650);
DISPLAY INVISIBLE (-950 3650);
FORCEPROP 1 LAST BODY_TYPE PLUMBING
J 2
(-950 3700);
DISPLAY 0.872340 (-950 3700);
PAINT GREEN (-950 3700);
DISPLAY INVISIBLE (-950 3700);
FORCEPROP 1 LAST HDL_TAP TRUE
J 2
(-1275 3525);
DISPLAY 0.872340 (-1275 3525);
DISPLAY INVISIBLE (-1275 3525);
FORCEPROP 1 LAST PATH I86
J 2
(-948 3650);
DISPLAY 0.872340 (-948 3650);
PAINT GREEN (-948 3650);
DISPLAY INVISIBLE (-948 3650);
FORCEADD TAP..1
R 2
(-950 3750);
FORCEPROP 3 LASTPIN (-900 3750) SIG_NAME M_B_CPU1_SA_DQ<28>
J 0
(-890 3760);
DISPLAY 0.659574 (-890 3760);
PAINT MONO (-890 3760);
DISPLAY INVISIBLE (-890 3760);
FORCEPROP 1 LASTPIN (-900 3750) BN 28
J 2
(-888 3758);
DISPLAY 0.680851 (-888 3758);
PAINT GREEN (-888 3758);
FORCEPROP 2 LAST CDS_LIB standard
J 0
(-950 3750);
DISPLAY INVISIBLE (-950 3750);
FORCEPROP 1 LAST BODY_TYPE PLUMBING
J 2
(-950 3800);
DISPLAY 0.872340 (-950 3800);
PAINT GREEN (-950 3800);
DISPLAY INVISIBLE (-950 3800);
FORCEPROP 1 LAST HDL_TAP TRUE
J 2
(-1275 3625);
DISPLAY 0.872340 (-1275 3625);
DISPLAY INVISIBLE (-1275 3625);
FORCEPROP 1 LAST PATH I87
J 2
(-948 3750);
DISPLAY 0.872340 (-948 3750);
PAINT GREEN (-948 3750);
DISPLAY INVISIBLE (-948 3750);
FORCEADD TAP..1
R 2
(-950 3800);
FORCEPROP 3 LASTPIN (-900 3800) SIG_NAME M_B_CPU1_SA_DQ<29>
J 0
(-890 3810);
DISPLAY 0.659574 (-890 3810);
PAINT MONO (-890 3810);
DISPLAY INVISIBLE (-890 3810);
FORCEPROP 1 LASTPIN (-900 3800) BN 29
J 2
(-888 3808);
DISPLAY 0.680851 (-888 3808);
PAINT GREEN (-888 3808);
FORCEPROP 2 LAST CDS_LIB standard
J 0
(-950 3800);
DISPLAY INVISIBLE (-950 3800);
FORCEPROP 1 LAST BODY_TYPE PLUMBING
J 2
(-950 3850);
DISPLAY 0.872340 (-950 3850);
PAINT GREEN (-950 3850);
DISPLAY INVISIBLE (-950 3850);
FORCEPROP 1 LAST HDL_TAP TRUE
J 2
(-1275 3675);
DISPLAY 0.872340 (-1275 3675);
DISPLAY INVISIBLE (-1275 3675);
FORCEPROP 1 LAST PATH I88
J 2
(-948 3800);
DISPLAY 0.872340 (-948 3800);
PAINT GREEN (-948 3800);
DISPLAY INVISIBLE (-948 3800);
FORCEADD TAP..1
R 2
(-950 3850);
FORCEPROP 3 LASTPIN (-900 3850) SIG_NAME M_B_CPU1_SA_DQ<30>
J 0
(-890 3860);
DISPLAY 0.659574 (-890 3860);
PAINT MONO (-890 3860);
DISPLAY INVISIBLE (-890 3860);
FORCEPROP 1 LASTPIN (-900 3850) BN 30
J 2
(-888 3858);
DISPLAY 0.680851 (-888 3858);
PAINT GREEN (-888 3858);
FORCEPROP 2 LAST CDS_LIB standard
J 0
(-950 3850);
DISPLAY INVISIBLE (-950 3850);
FORCEPROP 1 LAST BODY_TYPE PLUMBING
J 2
(-950 3900);
DISPLAY 0.872340 (-950 3900);
PAINT GREEN (-950 3900);
DISPLAY INVISIBLE (-950 3900);
FORCEPROP 1 LAST HDL_TAP TRUE
J 2
(-1275 3725);
DISPLAY 0.872340 (-1275 3725);
DISPLAY INVISIBLE (-1275 3725);
FORCEPROP 1 LAST PATH I89
J 2
(-948 3850);
DISPLAY 0.872340 (-948 3850);
PAINT GREEN (-948 3850);
DISPLAY INVISIBLE (-948 3850);
FORCEADD TAP..1
R 2
(-950 0);
FORCEPROP 3 LASTPIN (-900 0) SIG_NAME M_B_CPU1_SB_CB<1>
J 0
(-890 10);
DISPLAY 0.659574 (-890 10);
PAINT MONO (-890 10);
DISPLAY INVISIBLE (-890 10);
FORCEPROP 1 LASTPIN (-900 0) BN 1
J 2
(-888 8);
DISPLAY 0.680851 (-888 8);
PAINT GREEN (-888 8);
FORCEPROP 2 LAST CDS_LIB standard
J 0
(-950 0);
DISPLAY INVISIBLE (-950 0);
FORCEPROP 1 LAST BODY_TYPE PLUMBING
J 2
(-950 50);
DISPLAY 0.872340 (-950 50);
PAINT GREEN (-950 50);
DISPLAY INVISIBLE (-950 50);
FORCEPROP 1 LAST HDL_TAP TRUE
J 2
(-1275 -125);
DISPLAY 0.872340 (-1275 -125);
DISPLAY INVISIBLE (-1275 -125);
FORCEPROP 1 LAST PATH I9
J 2
(-948 0);
DISPLAY 0.872340 (-948 0);
PAINT GREEN (-948 0);
DISPLAY INVISIBLE (-948 0);
FORCEADD TAP..1
R 2
(-950 3900);
FORCEPROP 3 LASTPIN (-900 3900) SIG_NAME M_B_CPU1_SA_DQ<31>
J 0
(-890 3910);
DISPLAY 0.659574 (-890 3910);
PAINT MONO (-890 3910);
DISPLAY INVISIBLE (-890 3910);
FORCEPROP 1 LASTPIN (-900 3900) BN 31
J 2
(-888 3908);
DISPLAY 0.680851 (-888 3908);
PAINT GREEN (-888 3908);
FORCEPROP 2 LAST CDS_LIB standard
J 0
(-950 3900);
DISPLAY INVISIBLE (-950 3900);
FORCEPROP 1 LAST BODY_TYPE PLUMBING
J 2
(-950 3950);
DISPLAY 0.872340 (-950 3950);
PAINT GREEN (-950 3950);
DISPLAY INVISIBLE (-950 3950);
FORCEPROP 1 LAST HDL_TAP TRUE
J 2
(-1275 3775);
DISPLAY 0.872340 (-1275 3775);
DISPLAY INVISIBLE (-1275 3775);
FORCEPROP 1 LAST PATH I90
J 2
(-948 3900);
DISPLAY 0.872340 (-948 3900);
PAINT GREEN (-948 3900);
DISPLAY INVISIBLE (-948 3900);
FORCEADD SOCKET4677_AZIF0045P001C01CS..9
(775 1800);
FORCEPROP 1 LAST PART_NUMBER DGA^7000023
J 0
(-325 4150);
DISPLAY 0.723404 (-325 4150);
PAINT GREEN (-325 4150);
DISPLAY INVISIBLE (-325 4150);
FORCEPROP 2 LAST PART_TYPE SMLF
J 0
(-325 4325);
DISPLAY 1.021277 (-325 4325);
FORCEPROP 1 LAST MATERIAL IO
J 0
(-325 4075);
DISPLAY 0.723404 (-325 4075);
PAINT GREEN (-325 4075);
FORCEPROP 2 LAST VALUE SOCKET4677_AZIF0045-P001C01CS
J 0
(-325 4275);
DISPLAY 1.021277 (-325 4275);
FORCEPROP 1 LAST $LOCATION U1
J 0
(-325 4225);
DISPLAY 0.723404 (-325 4225);
PAINT GREEN (-325 4225);
FORCEPROP 0 LASTPIN (2000 -50) $PN AL48
J 0
(2010 -40);
DISPLAY 0.680851 (2010 -40);
PAINT MONO (2010 -40);
FORCEPROP 0 LASTPIN (2000 0) $PN AK47
J 0
(2010 10);
DISPLAY 0.680851 (2010 10);
PAINT MONO (2010 10);
FORCEPROP 0 LASTPIN (2000 -300) $PN AV49
J 0
(2010 -290);
DISPLAY 0.680851 (2010 -290);
PAINT MONO (2010 -290);
FORCEPROP 0 LASTPIN (2000 -200) $PN AN48
J 0
(2010 -190);
DISPLAY 0.680851 (2010 -190);
PAINT MONO (2010 -190);
FORCEPROP 0 LASTPIN (2000 -150) $PN AP47
J 0
(2010 -140);
DISPLAY 0.680851 (2010 -140);
PAINT MONO (2010 -140);
FORCEPROP 0 LASTPIN (-450 -300) $PN R45
J 2
(-460 -290);
DISPLAY 0.680851 (-460 -290);
PAINT MONO (-460 -290);
FORCEPROP 0 LASTPIN (-450 -250) $PN W45
J 2
(-460 -240);
DISPLAY 0.680851 (-460 -240);
PAINT MONO (-460 -240);
FORCEPROP 0 LASTPIN (-450 -200) $PN U45
J 2
(-460 -190);
DISPLAY 0.680851 (-460 -190);
PAINT MONO (-460 -190);
FORCEPROP 0 LASTPIN (-450 -150) $PN AA45
J 2
(-460 -140);
DISPLAY 0.680851 (-460 -140);
PAINT MONO (-460 -140);
FORCEPROP 0 LASTPIN (2000 1300) $PN H49
J 0
(2010 1310);
DISPLAY 0.680851 (2010 1310);
PAINT MONO (2010 1310);
FORCEPROP 0 LASTPIN (2000 1350) $PN P49
J 0
(2010 1360);
DISPLAY 0.680851 (2010 1360);
PAINT MONO (2010 1360);
FORCEPROP 0 LASTPIN (2000 1400) $PN J48
J 0
(2010 1410);
DISPLAY 0.680851 (2010 1410);
PAINT MONO (2010 1410);
FORCEPROP 0 LASTPIN (2000 1450) $PN N48
J 0
(2010 1460);
DISPLAY 0.680851 (2010 1460);
PAINT MONO (2010 1460);
FORCEPROP 0 LASTPIN (2000 1500) $PN K47
J 0
(2010 1510);
DISPLAY 0.680851 (2010 1510);
PAINT MONO (2010 1510);
FORCEPROP 0 LASTPIN (2000 1550) $PN M47
J 0
(2010 1560);
DISPLAY 0.680851 (2010 1560);
PAINT MONO (2010 1560);
FORCEPROP 0 LASTPIN (2000 1600) $PN Y44
J 0
(2010 1610);
DISPLAY 0.680851 (2010 1610);
PAINT MONO (2010 1610);
FORCEPROP 0 LASTPIN (-450 2350) $PN K75
J 2
(-460 2360);
DISPLAY 0.680851 (-460 2360);
PAINT MONO (-460 2360);
FORCEPROP 0 LASTPIN (-450 2400) $PN J74
J 2
(-460 2410);
DISPLAY 0.680851 (-460 2410);
PAINT MONO (-460 2410);
FORCEPROP 0 LASTPIN (-450 2450) $PN M75
J 2
(-460 2460);
DISPLAY 0.680851 (-460 2460);
PAINT MONO (-460 2460);
FORCEPROP 0 LASTPIN (-450 2500) $PN N74
J 2
(-460 2510);
DISPLAY 0.680851 (-460 2510);
PAINT MONO (-460 2510);
FORCEPROP 0 LASTPIN (-450 2550) $PN J72
J 2
(-460 2560);
DISPLAY 0.680851 (-460 2560);
PAINT MONO (-460 2560);
FORCEPROP 0 LASTPIN (-450 2600) $PN K71
J 2
(-460 2610);
DISPLAY 0.680851 (-460 2610);
PAINT MONO (-460 2610);
FORCEPROP 0 LASTPIN (-450 2650) $PN N72
J 2
(-460 2660);
DISPLAY 0.680851 (-460 2660);
PAINT MONO (-460 2660);
FORCEPROP 0 LASTPIN (-450 2700) $PN M71
J 2
(-460 2710);
DISPLAY 0.680851 (-460 2710);
PAINT MONO (-460 2710);
FORCEPROP 0 LASTPIN (-450 2750) $PN U72
J 2
(-460 2760);
DISPLAY 0.680851 (-460 2760);
PAINT MONO (-460 2760);
FORCEPROP 0 LASTPIN (-450 2800) $PN T71
J 2
(-460 2810);
DISPLAY 0.680851 (-460 2810);
PAINT MONO (-460 2810);
FORCEPROP 0 LASTPIN (-450 2850) $PN W72
J 2
(-460 2860);
DISPLAY 0.680851 (-460 2860);
PAINT MONO (-460 2860);
FORCEPROP 0 LASTPIN (-450 2900) $PN Y71
J 2
(-460 2910);
DISPLAY 0.680851 (-460 2910);
PAINT MONO (-460 2910);
FORCEPROP 0 LASTPIN (-450 2950) $PN T69
J 2
(-460 2960);
DISPLAY 0.680851 (-460 2960);
PAINT MONO (-460 2960);
FORCEPROP 0 LASTPIN (-450 3000) $PN U68
J 2
(-460 3010);
DISPLAY 0.680851 (-460 3010);
PAINT MONO (-460 3010);
FORCEPROP 0 LASTPIN (-450 3050) $PN Y69
J 2
(-460 3060);
DISPLAY 0.680851 (-460 3060);
PAINT MONO (-460 3060);
FORCEPROP 0 LASTPIN (-450 3100) $PN W68
J 2
(-460 3110);
DISPLAY 0.680851 (-460 3110);
PAINT MONO (-460 3110);
FORCEPROP 0 LASTPIN (-450 3150) $PN K63
J 2
(-460 3160);
DISPLAY 0.680851 (-460 3160);
PAINT MONO (-460 3160);
FORCEPROP 0 LASTPIN (-450 3200) $PN J62
J 2
(-460 3210);
DISPLAY 0.680851 (-460 3210);
PAINT MONO (-460 3210);
FORCEPROP 0 LASTPIN (-450 3250) $PN M63
J 2
(-460 3260);
DISPLAY 0.680851 (-460 3260);
PAINT MONO (-460 3260);
FORCEPROP 0 LASTPIN (-450 3300) $PN N62
J 2
(-460 3310);
DISPLAY 0.680851 (-460 3310);
PAINT MONO (-460 3310);
FORCEPROP 0 LASTPIN (-450 3350) $PN J60
J 2
(-460 3360);
DISPLAY 0.680851 (-460 3360);
PAINT MONO (-460 3360);
FORCEPROP 0 LASTPIN (-450 3400) $PN K59
J 2
(-460 3410);
DISPLAY 0.680851 (-460 3410);
PAINT MONO (-460 3410);
FORCEPROP 0 LASTPIN (-450 3450) $PN N60
J 2
(-460 3460);
DISPLAY 0.680851 (-460 3460);
PAINT MONO (-460 3460);
FORCEPROP 0 LASTPIN (-450 3500) $PN M59
J 2
(-460 3510);
DISPLAY 0.680851 (-460 3510);
PAINT MONO (-460 3510);
FORCEPROP 0 LASTPIN (-450 3550) $PN U60
J 2
(-460 3560);
DISPLAY 0.680851 (-460 3560);
PAINT MONO (-460 3560);
FORCEPROP 0 LASTPIN (-450 3600) $PN T59
J 2
(-460 3610);
DISPLAY 0.680851 (-460 3610);
PAINT MONO (-460 3610);
FORCEPROP 0 LASTPIN (-450 3650) $PN W60
J 2
(-460 3660);
DISPLAY 0.680851 (-460 3660);
PAINT MONO (-460 3660);
FORCEPROP 0 LASTPIN (-450 3700) $PN Y59
J 2
(-460 3710);
DISPLAY 0.680851 (-460 3710);
PAINT MONO (-460 3710);
FORCEPROP 0 LASTPIN (-450 3750) $PN T57
J 2
(-460 3760);
DISPLAY 0.680851 (-460 3760);
PAINT MONO (-460 3760);
FORCEPROP 0 LASTPIN (-450 3800) $PN U56
J 2
(-460 3810);
DISPLAY 0.680851 (-460 3810);
PAINT MONO (-460 3810);
FORCEPROP 0 LASTPIN (-450 3850) $PN Y57
J 2
(-460 3860);
DISPLAY 0.680851 (-460 3860);
PAINT MONO (-460 3860);
FORCEPROP 0 LASTPIN (-450 3900) $PN W56
J 2
(-460 3910);
DISPLAY 0.680851 (-460 3910);
PAINT MONO (-460 3910);
FORCEPROP 0 LASTPIN (2000 2900) $PN H73
J 0
(2010 2910);
DISPLAY 0.680851 (2010 2910);
PAINT MONO (2010 2910);
FORCEPROP 0 LASTPIN (2000 2950) $PN R70
J 0
(2010 2960);
DISPLAY 0.680851 (2010 2960);
PAINT MONO (2010 2960);
FORCEPROP 0 LASTPIN (2000 3000) $PN H61
J 0
(2010 3010);
DISPLAY 0.680851 (2010 3010);
PAINT MONO (2010 3010);
FORCEPROP 0 LASTPIN (2000 3050) $PN R58
J 0
(2010 3060);
DISPLAY 0.680851 (2010 3060);
PAINT MONO (2010 3060);
FORCEPROP 0 LASTPIN (2000 3100) $PN H55
J 0
(2010 3110);
DISPLAY 0.680851 (2010 3110);
PAINT MONO (2010 3110);
FORCEPROP 0 LASTPIN (2000 3150) $PN M73
J 0
(2010 3160);
DISPLAY 0.680851 (2010 3160);
PAINT MONO (2010 3160);
FORCEPROP 0 LASTPIN (2000 3200) $PN AA70
J 0
(2010 3210);
DISPLAY 0.680851 (2010 3210);
PAINT MONO (2010 3210);
FORCEPROP 0 LASTPIN (2000 3250) $PN M61
J 0
(2010 3260);
DISPLAY 0.680851 (2010 3260);
PAINT MONO (2010 3260);
FORCEPROP 0 LASTPIN (2000 3300) $PN AA58
J 0
(2010 3310);
DISPLAY 0.680851 (2010 3310);
PAINT MONO (2010 3310);
FORCEPROP 0 LASTPIN (2000 3350) $PN M55
J 0
(2010 3360);
DISPLAY 0.680851 (2010 3360);
PAINT MONO (2010 3360);
FORCEPROP 0 LASTPIN (2000 3450) $PN K73
J 0
(2010 3460);
DISPLAY 0.680851 (2010 3460);
PAINT MONO (2010 3460);
FORCEPROP 0 LASTPIN (2000 3500) $PN U70
J 0
(2010 3510);
DISPLAY 0.680851 (2010 3510);
PAINT MONO (2010 3510);
FORCEPROP 0 LASTPIN (2000 3550) $PN K61
J 0
(2010 3560);
DISPLAY 0.680851 (2010 3560);
PAINT MONO (2010 3560);
FORCEPROP 0 LASTPIN (2000 3600) $PN U58
J 0
(2010 3610);
DISPLAY 0.680851 (2010 3610);
PAINT MONO (2010 3610);
FORCEPROP 0 LASTPIN (2000 3650) $PN K55
J 0
(2010 3660);
DISPLAY 0.680851 (2010 3660);
PAINT MONO (2010 3660);
FORCEPROP 0 LASTPIN (2000 3700) $PN P73
J 0
(2010 3710);
DISPLAY 0.680851 (2010 3710);
PAINT MONO (2010 3710);
FORCEPROP 0 LASTPIN (2000 3750) $PN W70
J 0
(2010 3760);
DISPLAY 0.680851 (2010 3760);
PAINT MONO (2010 3760);
FORCEPROP 0 LASTPIN (2000 3800) $PN P61
J 0
(2010 3810);
DISPLAY 0.680851 (2010 3810);
PAINT MONO (2010 3810);
FORCEPROP 0 LASTPIN (2000 3850) $PN W58
J 0
(2010 3860);
DISPLAY 0.680851 (2010 3860);
PAINT MONO (2010 3860);
FORCEPROP 0 LASTPIN (2000 3900) $PN P55
J 0
(2010 3910);
DISPLAY 0.680851 (2010 3910);
PAINT MONO (2010 3910);
FORCEPROP 0 LASTPIN (-450 1950) $PN K57
J 2
(-460 1960);
DISPLAY 0.680851 (-460 1960);
PAINT MONO (-460 1960);
FORCEPROP 0 LASTPIN (-450 2000) $PN J56
J 2
(-460 2010);
DISPLAY 0.680851 (-460 2010);
PAINT MONO (-460 2010);
FORCEPROP 0 LASTPIN (-450 2050) $PN M57
J 2
(-460 2060);
DISPLAY 0.680851 (-460 2060);
PAINT MONO (-460 2060);
FORCEPROP 0 LASTPIN (-450 2100) $PN N56
J 2
(-460 2110);
DISPLAY 0.680851 (-460 2110);
PAINT MONO (-460 2110);
FORCEPROP 0 LASTPIN (-450 2150) $PN J54
J 2
(-460 2160);
DISPLAY 0.680851 (-460 2160);
PAINT MONO (-460 2160);
FORCEPROP 0 LASTPIN (-450 2200) $PN K53
J 2
(-460 2210);
DISPLAY 0.680851 (-460 2210);
PAINT MONO (-460 2210);
FORCEPROP 0 LASTPIN (-450 2250) $PN N54
J 2
(-460 2260);
DISPLAY 0.680851 (-460 2260);
PAINT MONO (-460 2260);
FORCEPROP 0 LASTPIN (-450 2300) $PN M53
J 2
(-460 2310);
DISPLAY 0.680851 (-460 2310);
PAINT MONO (-460 2310);
FORCEPROP 0 LASTPIN (2000 1250) $PN W43
J 0
(2010 1260);
DISPLAY 0.680851 (2010 1260);
PAINT MONO (2010 1260);
FORCEPROP 0 LASTPIN (2000 800) $PN T44
J 0
(2010 810);
DISPLAY 0.680851 (2010 810);
PAINT MONO (2010 810);
FORCEPROP 0 LASTPIN (2000 850) $PN U43
J 0
(2010 860);
DISPLAY 0.680851 (2010 860);
PAINT MONO (2010 860);
FORCEPROP 0 LASTPIN (2000 900) $PN K44
J 0
(2010 910);
DISPLAY 0.680851 (2010 910);
PAINT MONO (2010 910);
FORCEPROP 0 LASTPIN (2000 950) $PN M44
J 0
(2010 960);
DISPLAY 0.680851 (2010 960);
PAINT MONO (2010 960);
FORCEPROP 0 LASTPIN (2000 1000) $PN J43
J 0
(2010 1010);
DISPLAY 0.680851 (2010 1010);
PAINT MONO (2010 1010);
FORCEPROP 0 LASTPIN (2000 1050) $PN N43
J 0
(2010 1060);
DISPLAY 0.680851 (2010 1060);
PAINT MONO (2010 1060);
FORCEPROP 0 LASTPIN (2000 1100) $PN H42
J 0
(2010 1110);
DISPLAY 0.680851 (2010 1110);
PAINT MONO (2010 1110);
FORCEPROP 0 LASTPIN (-450 350) $PN U29
J 2
(-460 360);
DISPLAY 0.680851 (-460 360);
PAINT MONO (-460 360);
FORCEPROP 0 LASTPIN (-450 400) $PN T28
J 2
(-460 410);
DISPLAY 0.680851 (-460 410);
PAINT MONO (-460 410);
FORCEPROP 0 LASTPIN (-450 450) $PN W29
J 2
(-460 460);
DISPLAY 0.680851 (-460 460);
PAINT MONO (-460 460);
FORCEPROP 0 LASTPIN (-450 500) $PN Y28
J 2
(-460 510);
DISPLAY 0.680851 (-460 510);
PAINT MONO (-460 510);
FORCEPROP 0 LASTPIN (-450 550) $PN T26
J 2
(-460 560);
DISPLAY 0.680851 (-460 560);
PAINT MONO (-460 560);
FORCEPROP 0 LASTPIN (-450 600) $PN U25
J 2
(-460 610);
DISPLAY 0.680851 (-460 610);
PAINT MONO (-460 610);
FORCEPROP 0 LASTPIN (-450 650) $PN Y26
J 2
(-460 660);
DISPLAY 0.680851 (-460 660);
PAINT MONO (-460 660);
FORCEPROP 0 LASTPIN (-450 700) $PN W25
J 2
(-460 710);
DISPLAY 0.680851 (-460 710);
PAINT MONO (-460 710);
FORCEPROP 0 LASTPIN (-450 750) $PN K26
J 2
(-460 760);
DISPLAY 0.680851 (-460 760);
PAINT MONO (-460 760);
FORCEPROP 0 LASTPIN (-450 800) $PN J25
J 2
(-460 810);
DISPLAY 0.680851 (-460 810);
PAINT MONO (-460 810);
FORCEPROP 0 LASTPIN (-450 850) $PN M26
J 2
(-460 860);
DISPLAY 0.680851 (-460 860);
PAINT MONO (-460 860);
FORCEPROP 0 LASTPIN (-450 900) $PN N25
J 2
(-460 910);
DISPLAY 0.680851 (-460 910);
PAINT MONO (-460 910);
FORCEPROP 0 LASTPIN (-450 950) $PN J23
J 2
(-460 960);
DISPLAY 0.680851 (-460 960);
PAINT MONO (-460 960);
FORCEPROP 0 LASTPIN (-450 1000) $PN K22
J 2
(-460 1010);
DISPLAY 0.680851 (-460 1010);
PAINT MONO (-460 1010);
FORCEPROP 0 LASTPIN (-450 1050) $PN N23
J 2
(-460 1060);
DISPLAY 0.680851 (-460 1060);
PAINT MONO (-460 1060);
FORCEPROP 0 LASTPIN (-450 1100) $PN M22
J 2
(-460 1110);
DISPLAY 0.680851 (-460 1110);
PAINT MONO (-460 1110);
FORCEPROP 0 LASTPIN (-450 1150) $PN K20
J 2
(-460 1160);
DISPLAY 0.680851 (-460 1160);
PAINT MONO (-460 1160);
FORCEPROP 0 LASTPIN (-450 1200) $PN J19
J 2
(-460 1210);
DISPLAY 0.680851 (-460 1210);
PAINT MONO (-460 1210);
FORCEPROP 0 LASTPIN (-450 1250) $PN M20
J 2
(-460 1260);
DISPLAY 0.680851 (-460 1260);
PAINT MONO (-460 1260);
FORCEPROP 0 LASTPIN (-450 1300) $PN N19
J 2
(-460 1310);
DISPLAY 0.680851 (-460 1310);
PAINT MONO (-460 1310);
FORCEPROP 0 LASTPIN (-450 1350) $PN J17
J 2
(-460 1360);
DISPLAY 0.680851 (-460 1360);
PAINT MONO (-460 1360);
FORCEPROP 0 LASTPIN (-450 1400) $PN K16
J 2
(-460 1410);
DISPLAY 0.680851 (-460 1410);
PAINT MONO (-460 1410);
FORCEPROP 0 LASTPIN (-450 1450) $PN N17
J 2
(-460 1460);
DISPLAY 0.680851 (-460 1460);
PAINT MONO (-460 1460);
FORCEPROP 0 LASTPIN (-450 1500) $PN M16
J 2
(-460 1510);
DISPLAY 0.680851 (-460 1510);
PAINT MONO (-460 1510);
FORCEPROP 0 LASTPIN (-450 1550) $PN C17
J 2
(-460 1560);
DISPLAY 0.680851 (-460 1560);
PAINT MONO (-460 1560);
FORCEPROP 0 LASTPIN (-450 1600) $PN B16
J 2
(-460 1610);
DISPLAY 0.680851 (-460 1610);
PAINT MONO (-460 1610);
FORCEPROP 0 LASTPIN (-450 1650) $PN E17
J 2
(-460 1660);
DISPLAY 0.680851 (-460 1660);
PAINT MONO (-460 1660);
FORCEPROP 0 LASTPIN (-450 1700) $PN F16
J 2
(-460 1710);
DISPLAY 0.680851 (-460 1710);
PAINT MONO (-460 1710);
FORCEPROP 0 LASTPIN (-450 1750) $PN C13
J 2
(-460 1760);
DISPLAY 0.680851 (-460 1760);
PAINT MONO (-460 1760);
FORCEPROP 0 LASTPIN (-450 1800) $PN E13
J 2
(-460 1810);
DISPLAY 0.680851 (-460 1810);
PAINT MONO (-460 1810);
FORCEPROP 0 LASTPIN (-450 1850) $PN B14
J 2
(-460 1860);
DISPLAY 0.680851 (-460 1860);
PAINT MONO (-460 1860);
FORCEPROP 0 LASTPIN (-450 1900) $PN F14
J 2
(-460 1910);
DISPLAY 0.680851 (-460 1910);
PAINT MONO (-460 1910);
FORCEPROP 0 LASTPIN (2000 1750) $PN R27
J 0
(2010 1760);
DISPLAY 0.680851 (2010 1760);
PAINT MONO (2010 1760);
FORCEPROP 0 LASTPIN (2000 1800) $PN H24
J 0
(2010 1810);
DISPLAY 0.680851 (2010 1810);
PAINT MONO (2010 1810);
FORCEPROP 0 LASTPIN (2000 1850) $PN H18
J 0
(2010 1860);
DISPLAY 0.680851 (2010 1860);
PAINT MONO (2010 1860);
FORCEPROP 0 LASTPIN (2000 1900) $PN A15
J 0
(2010 1910);
DISPLAY 0.680851 (2010 1910);
PAINT MONO (2010 1910);
FORCEPROP 0 LASTPIN (2000 1950) $PN P36
J 0
(2010 1960);
DISPLAY 0.680851 (2010 1960);
PAINT MONO (2010 1960);
FORCEPROP 0 LASTPIN (2000 2000) $PN W27
J 0
(2010 2010);
DISPLAY 0.680851 (2010 2010);
PAINT MONO (2010 2010);
FORCEPROP 0 LASTPIN (2000 2050) $PN M24
J 0
(2010 2060);
DISPLAY 0.680851 (2010 2060);
PAINT MONO (2010 2060);
FORCEPROP 0 LASTPIN (2000 2100) $PN M18
J 0
(2010 2110);
DISPLAY 0.680851 (2010 2110);
PAINT MONO (2010 2110);
FORCEPROP 0 LASTPIN (2000 2150) $PN E15
J 0
(2010 2160);
DISPLAY 0.680851 (2010 2160);
PAINT MONO (2010 2160);
FORCEPROP 0 LASTPIN (2000 2200) $PN K36
J 0
(2010 2210);
DISPLAY 0.680851 (2010 2210);
PAINT MONO (2010 2210);
FORCEPROP 0 LASTPIN (2000 2300) $PN U27
J 0
(2010 2310);
DISPLAY 0.680851 (2010 2310);
PAINT MONO (2010 2310);
FORCEPROP 0 LASTPIN (2000 2350) $PN K24
J 0
(2010 2360);
DISPLAY 0.680851 (2010 2360);
PAINT MONO (2010 2360);
FORCEPROP 0 LASTPIN (2000 2400) $PN K18
J 0
(2010 2410);
DISPLAY 0.680851 (2010 2410);
PAINT MONO (2010 2410);
FORCEPROP 0 LASTPIN (2000 2450) $PN C15
J 0
(2010 2460);
DISPLAY 0.680851 (2010 2460);
PAINT MONO (2010 2460);
FORCEPROP 0 LASTPIN (2000 2500) $PN M36
J 0
(2010 2510);
DISPLAY 0.680851 (2010 2510);
PAINT MONO (2010 2510);
FORCEPROP 0 LASTPIN (2000 2550) $PN AA27
J 0
(2010 2560);
DISPLAY 0.680851 (2010 2560);
PAINT MONO (2010 2560);
FORCEPROP 0 LASTPIN (2000 2600) $PN P24
J 0
(2010 2610);
DISPLAY 0.680851 (2010 2610);
PAINT MONO (2010 2610);
FORCEPROP 0 LASTPIN (2000 2650) $PN P18
J 0
(2010 2660);
DISPLAY 0.680851 (2010 2660);
PAINT MONO (2010 2660);
FORCEPROP 0 LASTPIN (2000 2700) $PN G15
J 0
(2010 2710);
DISPLAY 0.680851 (2010 2710);
PAINT MONO (2010 2710);
FORCEPROP 0 LASTPIN (2000 2750) $PN H36
J 0
(2010 2760);
DISPLAY 0.680851 (2010 2760);
PAINT MONO (2010 2760);
FORCEPROP 0 LASTPIN (-450 -50) $PN J35
J 2
(-460 -40);
DISPLAY 0.680851 (-460 -40);
PAINT MONO (-460 -40);
FORCEPROP 0 LASTPIN (-450 0) $PN K34
J 2
(-460 10);
DISPLAY 0.680851 (-460 10);
PAINT MONO (-460 10);
FORCEPROP 0 LASTPIN (-450 50) $PN N35
J 2
(-460 60);
DISPLAY 0.680851 (-460 60);
PAINT MONO (-460 60);
FORCEPROP 0 LASTPIN (-450 100) $PN M34
J 2
(-460 110);
DISPLAY 0.680851 (-460 110);
PAINT MONO (-460 110);
FORCEPROP 0 LASTPIN (-450 150) $PN K38
J 2
(-460 160);
DISPLAY 0.680851 (-460 160);
PAINT MONO (-460 160);
FORCEPROP 0 LASTPIN (-450 200) $PN J37
J 2
(-460 210);
DISPLAY 0.680851 (-460 210);
PAINT MONO (-460 210);
FORCEPROP 0 LASTPIN (-450 250) $PN M38
J 2
(-460 260);
DISPLAY 0.680851 (-460 260);
PAINT MONO (-460 260);
FORCEPROP 0 LASTPIN (-450 300) $PN N37
J 2
(-460 310);
DISPLAY 0.680851 (-460 310);
PAINT MONO (-460 310);
FORCEPROP 0 LASTPIN (2000 750) $PN P42
J 0
(2010 760);
DISPLAY 0.680851 (2010 760);
PAINT MONO (2010 760);
FORCEPROP 0 LASTPIN (2000 450) $PN K51
J 0
(2010 460);
DISPLAY 0.680851 (2010 460);
PAINT MONO (2010 460);
FORCEPROP 0 LASTPIN (2000 500) $PN J50
J 0
(2010 510);
DISPLAY 0.680851 (2010 510);
PAINT MONO (2010 510);
FORCEPROP 0 LASTPIN (2000 550) $PN M51
J 0
(2010 560);
DISPLAY 0.680851 (2010 560);
PAINT MONO (2010 560);
FORCEPROP 0 LASTPIN (2000 600) $PN N50
J 0
(2010 610);
DISPLAY 0.680851 (2010 610);
PAINT MONO (2010 610);
FORCEPROP 0 LASTPIN (2000 150) $PN J41
J 0
(2010 160);
DISPLAY 0.680851 (2010 160);
PAINT MONO (2010 160);
FORCEPROP 0 LASTPIN (2000 200) $PN K40
J 0
(2010 210);
DISPLAY 0.680851 (2010 210);
PAINT MONO (2010 210);
FORCEPROP 0 LASTPIN (2000 250) $PN N41
J 0
(2010 260);
DISPLAY 0.680851 (2010 260);
PAINT MONO (2010 260);
FORCEPROP 0 LASTPIN (2000 300) $PN M40
J 0
(2010 310);
DISPLAY 0.680851 (2010 310);
PAINT MONO (2010 310);
FORCEPROP 2 LAST CDS_LIB pure_quanta
J 0
(775 1800);
DISPLAY INVISIBLE (775 1800);
FORCEPROP 1 LAST NEEDS_NO_SIZE TRUE
J 0
(775 1800);
DISPLAY 0.723404 (775 1800);
PAINT GREEN (775 1800);
DISPLAY INVISIBLE (775 1800);
FORCEPROP 1 LAST CDS_LMAN_SYM_OUTLINE -1100,2250,1050,-2250
J 0
(775 1800);
DISPLAY 0.468085 (775 1800);
PAINT GREEN (775 1800);
DISPLAY INVISIBLE (775 1800);
FORCEPROP 2 LAST CDS_LOCATION U1
J 0
(-325 4375);
DISPLAY 1.021277 (-325 4375);
DISPLAY INVISIBLE (-325 4375);
FORCEPROP 0 LAST $SEC 9
J 0
(-325 4375);
DISPLAY 0.680851 (-325 4375);
PAINT MONO (-325 4375);
DISPLAY INVISIBLE (-325 4375);
FORCEPROP 2 LAST CDS_SEC 9
J 0
(-325 4375);
DISPLAY 1.021277 (-325 4375);
DISPLAY INVISIBLE (-325 4375);
FORCEPROP 1 LAST PATH I91
J 0
(775 1800);
DISPLAY 0.723404 (775 1800);
PAINT GREEN (775 1800);
DISPLAY INVISIBLE (775 1800);
FORCEADD OFFPAGE..4
(3575 -300);
FORCEPROP 2 LAST $XR1 101 
J 0
(3881 -300);
DISPLAY 0.638298 (3881 -300);
PAINT MONO (3881 -300);
FORCEPROP 2 LAST $XR0 100 
J 0
(3761 -300);
DISPLAY 0.638298 (3761 -300);
PAINT MONO (3761 -300);
FORCEPROP 2 LAST CDS_LIB standard
J 0
(3575 -300);
PAINT MONO (3575 -300);
DISPLAY INVISIBLE (3575 -300);
FORCEPROP 1 LAST OFFPAGE TRUE
J 0
(3900 -425);
DISPLAY 1.170213 (3900 -425);
PAINT GREEN (3900 -425);
DISPLAY INVISIBLE (3900 -425);
FORCEPROP 1 LAST COMMENT_BODY TRUE
J 0
(3550 -400);
DISPLAY 1.170213 (3550 -400);
PAINT GREEN (3550 -400);
DISPLAY INVISIBLE (3550 -400);
FORCEPROP 2 LAST PATH I92
J 0
(3750 -225);
DISPLAY 1.021277 (3750 -225);
DISPLAY INVISIBLE (3750 -225);
FORCEADD OFFPAGE..4
(3575 -200);
FORCEPROP 2 LAST $XR0 100 
J 0
(3761 -200);
DISPLAY 0.638298 (3761 -200);
PAINT MONO (3761 -200);
FORCEPROP 2 LAST CDS_LIB standard
J 0
(3575 -200);
PAINT MONO (3575 -200);
DISPLAY INVISIBLE (3575 -200);
FORCEPROP 1 LAST OFFPAGE TRUE
J 0
(3900 -325);
DISPLAY 1.170213 (3900 -325);
PAINT GREEN (3900 -325);
DISPLAY INVISIBLE (3900 -325);
FORCEPROP 1 LAST COMMENT_BODY TRUE
J 0
(3550 -300);
DISPLAY 1.170213 (3550 -300);
PAINT GREEN (3550 -300);
DISPLAY INVISIBLE (3550 -300);
FORCEPROP 2 LAST PATH I93
J 0
(3750 -125);
DISPLAY 1.021277 (3750 -125);
DISPLAY INVISIBLE (3750 -125);
FORCEADD OFFPAGE..4
(3575 -150);
FORCEPROP 2 LAST $XR0 101 
J 0
(3761 -150);
DISPLAY 0.638298 (3761 -150);
PAINT MONO (3761 -150);
FORCEPROP 2 LAST CDS_LIB standard
J 0
(3575 -150);
PAINT MONO (3575 -150);
DISPLAY INVISIBLE (3575 -150);
FORCEPROP 1 LAST OFFPAGE TRUE
J 0
(3900 -275);
DISPLAY 1.170213 (3900 -275);
PAINT GREEN (3900 -275);
DISPLAY INVISIBLE (3900 -275);
FORCEPROP 1 LAST COMMENT_BODY TRUE
J 0
(3550 -250);
DISPLAY 1.170213 (3550 -250);
PAINT GREEN (3550 -250);
DISPLAY INVISIBLE (3550 -250);
FORCEPROP 2 LAST PATH I94
J 0
(3750 -75);
DISPLAY 1.021277 (3750 -75);
DISPLAY INVISIBLE (3750 -75);
FORCEADD OFFPAGE..4
(3575 -50);
FORCEPROP 2 LAST $XR0 100 
J 0
(3761 -50);
DISPLAY 0.638298 (3761 -50);
PAINT MONO (3761 -50);
FORCEPROP 2 LAST CDS_LIB standard
J 0
(3575 -50);
PAINT MONO (3575 -50);
DISPLAY INVISIBLE (3575 -50);
FORCEPROP 1 LAST OFFPAGE TRUE
J 0
(3900 -175);
DISPLAY 1.170213 (3900 -175);
PAINT GREEN (3900 -175);
DISPLAY INVISIBLE (3900 -175);
FORCEPROP 1 LAST COMMENT_BODY TRUE
J 0
(3550 -150);
DISPLAY 1.170213 (3550 -150);
PAINT GREEN (3550 -150);
DISPLAY INVISIBLE (3550 -150);
FORCEPROP 2 LAST PATH I95
J 0
(3750 25);
DISPLAY 1.021277 (3750 25);
DISPLAY INVISIBLE (3750 25);
FORCEADD TAP..1
(2475 150);
FORCEPROP 3 LASTPIN (2425 150) SIG_NAME M_B_CPU1_SB_CS_N<0>
J 0
(2435 160);
DISPLAY 0.659574 (2435 160);
PAINT MONO (2435 160);
DISPLAY INVISIBLE (2435 160);
FORCEPROP 1 LASTPIN (2425 150) BN 0
J 0
(2413 158);
DISPLAY 0.680851 (2413 158);
PAINT GREEN (2413 158);
FORCEPROP 2 LAST CDS_LIB standard
J 0
(2475 150);
DISPLAY INVISIBLE (2475 150);
FORCEPROP 1 LAST BODY_TYPE PLUMBING
J 0
(2475 200);
DISPLAY 0.872340 (2475 200);
PAINT GREEN (2475 200);
DISPLAY INVISIBLE (2475 200);
FORCEPROP 1 LAST HDL_TAP TRUE
J 0
(2800 25);
DISPLAY 0.872340 (2800 25);
DISPLAY INVISIBLE (2800 25);
FORCEPROP 1 LAST PATH I96
J 0
(2473 150);
DISPLAY 0.872340 (2473 150);
PAINT GREEN (2473 150);
DISPLAY INVISIBLE (2473 150);
FORCEADD TAP..1
(2475 200);
FORCEPROP 3 LASTPIN (2425 200) SIG_NAME M_B_CPU1_SB_CS_N<1>
J 0
(2435 210);
DISPLAY 0.659574 (2435 210);
PAINT MONO (2435 210);
DISPLAY INVISIBLE (2435 210);
FORCEPROP 1 LASTPIN (2425 200) BN 1
J 0
(2413 208);
DISPLAY 0.680851 (2413 208);
PAINT GREEN (2413 208);
FORCEPROP 2 LAST CDS_LIB standard
J 0
(2475 200);
DISPLAY INVISIBLE (2475 200);
FORCEPROP 1 LAST BODY_TYPE PLUMBING
J 0
(2475 250);
DISPLAY 0.872340 (2475 250);
PAINT GREEN (2475 250);
DISPLAY INVISIBLE (2475 250);
FORCEPROP 1 LAST HDL_TAP TRUE
J 0
(2800 75);
DISPLAY 0.872340 (2800 75);
DISPLAY INVISIBLE (2800 75);
FORCEPROP 1 LAST PATH I97
J 0
(2473 200);
DISPLAY 0.872340 (2473 200);
PAINT GREEN (2473 200);
DISPLAY INVISIBLE (2473 200);
FORCEADD TAP..1
(2475 300);
FORCEPROP 3 LASTPIN (2425 300) SIG_NAME M_B_CPU1_SB_CS_N<3>
J 0
(2435 310);
DISPLAY 0.659574 (2435 310);
PAINT MONO (2435 310);
DISPLAY INVISIBLE (2435 310);
FORCEPROP 1 LASTPIN (2425 300) BN 3
J 0
(2413 308);
DISPLAY 0.680851 (2413 308);
PAINT GREEN (2413 308);
FORCEPROP 2 LAST CDS_LIB standard
J 0
(2475 300);
DISPLAY INVISIBLE (2475 300);
FORCEPROP 1 LAST BODY_TYPE PLUMBING
J 0
(2475 350);
DISPLAY 0.872340 (2475 350);
PAINT GREEN (2475 350);
DISPLAY INVISIBLE (2475 350);
FORCEPROP 1 LAST HDL_TAP TRUE
J 0
(2800 175);
DISPLAY 0.872340 (2800 175);
DISPLAY INVISIBLE (2800 175);
FORCEPROP 1 LAST PATH I98
J 0
(2473 300);
DISPLAY 0.872340 (2473 300);
PAINT GREEN (2473 300);
DISPLAY INVISIBLE (2473 300);
FORCEADD TAP..1
(2475 250);
FORCEPROP 3 LASTPIN (2425 250) SIG_NAME M_B_CPU1_SB_CS_N<2>
J 0
(2435 260);
DISPLAY 0.659574 (2435 260);
PAINT MONO (2435 260);
DISPLAY INVISIBLE (2435 260);
FORCEPROP 1 LASTPIN (2425 250) BN 2
J 0
(2413 258);
DISPLAY 0.680851 (2413 258);
PAINT GREEN (2413 258);
FORCEPROP 2 LAST CDS_LIB standard
J 0
(2475 250);
DISPLAY INVISIBLE (2475 250);
FORCEPROP 1 LAST BODY_TYPE PLUMBING
J 0
(2475 300);
DISPLAY 0.872340 (2475 300);
PAINT GREEN (2475 300);
DISPLAY INVISIBLE (2475 300);
FORCEPROP 1 LAST HDL_TAP TRUE
J 0
(2800 125);
DISPLAY 0.872340 (2800 125);
DISPLAY INVISIBLE (2800 125);
FORCEPROP 1 LAST PATH I99
J 0
(2473 250);
DISPLAY 0.872340 (2473 250);
PAINT GREEN (2473 250);
DISPLAY INVISIBLE (2473 250);
FORCEADD QUANTA_TITLE_BLOCK_C..1
(5400 -1600);
FORCEPROP 0 LAST CDS_CON_LAST_MODIFIED Fri Aug 25 14:00:34 2023
J 0
(3515 -1585);
PAINT MONO (3515 -1585);
DISPLAY INVISIBLE (3515 -1585);
FORCEPROP 1 LAST CUSTOM_TXT_CDS <CON_LAST_MODIFIED>
J 0
(3515 -1585);
DISPLAY 0.978723 (3515 -1585);
FORCEPROP 2 LAST CUSTOM_TXT_CDS <XR_PAGE_TITLE>
J 0
(-2490 3650);
DISPLAY 0.638298 (-2490 3650);
PAINT PINK (-2490 3650);
DISPLAY INVISIBLE (-2490 3650);
FORCEPROP 2 LAST CUSTOM_TXT_CDS <CON_PAGE_NUM> OF <CON_TOTAL_PAGES>
J 0
(4954 -1582);
DISPLAY 0.978723 (4954 -1582);
FORCEPROP 2 LAST CUSTOM_TXT_CDS <Q_NUMBER>
J 0
(3997 -1497);
DISPLAY 1.212766 (3997 -1497);
FORCEPROP 2 LAST CUSTOM_TXT_CDS <Q_PROJ>
J 0
(3018 -1498);
DISPLAY 1.212766 (3018 -1498);
FORCEPROP 2 LAST CUSTOM_TXT_CDS <Q_REV>
J 0
(5216 -1497);
DISPLAY 1.212766 (5216 -1497);
FORCEPROP 1 LAST CUSTOM_TXT_CDS <NAME_2>
J 0
(2225 -1550);
FORCEPROP 1 LAST CUSTOM_TXT_CDS <NAME_1>
J 0
(2225 -1425);
FORCEPROP 1 LAST Q_TITLE SPR CPU1 - DDR CH B (9 OF 30)
J 0
(-3966 -1574);
DISPLAY 1.957447 (-3966 -1574);
PAINT GREEN (-3966 -1574);
FORCEPROP 1 LAST Q_DEPT 
J 1
(1637 -1551);
DISPLAY 1.957447 (1637 -1551);
PAINT GREEN (1637 -1551);
FORCEPROP 1 LAST COMMENT_BODY TRUE
J 0
(5412 -1613);
DISPLAY 0.978723 (5412 -1613);
PAINT GREEN (5412 -1613);
DISPLAY INVISIBLE (5412 -1613);
FORCEPROP 2 LAST CDS_XR_PAGE_TITLE CR-52 : @S9S_MB_2U_LIB.S9S_MB_2U(SCH_1):PAGE52
J 0
(-2490 3650);
DISPLAY 0.638298 (-2490 3650);
PAINT PINK (-2490 3650);
DISPLAY INVISIBLE (-2490 3650);
FORCEPROP 2 LAST PAGE_BORDER TRUE
J 0
(-2490 3650);
DISPLAY 0.638298 (-2490 3650);
PAINT PINK (-2490 3650);
DISPLAY INVISIBLE (-2490 3650);
FORCEPROP 1 LAST CDS_LMAN_SYM_OUTLINE -9475,6775,100,-125
J 0
(5400 -1600);
DISPLAY 0.468085 (5400 -1600);
PAINT GREEN (5400 -1600);
DISPLAY INVISIBLE (5400 -1600);
FORCEPROP 2 LAST CDS_LIB pure_quanta
J 0
(5400 -1600);
PAINT MONO (5400 -1600);
DISPLAY INVISIBLE (5400 -1600);
WIRE 17 -1 (2525 1625)(3525 1625);
FORCEPROP 2 LAST SIG_NAME M_B_CPU1_SA_CA<6:0>
J 0
(2665 1635);
DISPLAY 0.680851 (2665 1635);
PAINT WHITE (2665 1635);
WIRE 17 -1 (2525 1575)(2525 1625);
WIRE 17 -1 (2525 1525)(2525 1575);
WIRE 17 -1 (2525 1475)(2525 1525);
WIRE 17 -1 (2525 1425)(2525 1475);
WIRE 17 -1 (2525 1375)(2525 1425);
WIRE 17 -1 (2525 1325)(2525 1375);
WIRE 17 -1 (2525 625)(3525 625);
FORCEPROP 2 LAST SIG_NAME M_B_CPU1_SA_CS_N<3:0>
J 0
(2665 635);
DISPLAY 0.680851 (2665 635);
PAINT WHITE (2665 635);
WIRE 17 -1 (2525 575)(2525 625);
WIRE 17 -1 (2525 525)(2525 575);
WIRE 17 -1 (2525 475)(2525 525);
WIRE 17 -1 (2525 3375)(3525 3375);
FORCEPROP 2 LAST SIG_NAME M_B_CPU1_SA_DQS_DN<9:0>
J 0
(2665 3385);
DISPLAY 0.680851 (2665 3385);
PAINT WHITE (2665 3385);
WIRE 17 -1 (2525 3325)(2525 3375);
WIRE 17 -1 (2525 3275)(2525 3325);
WIRE 17 -1 (2525 3225)(2525 3275);
WIRE 17 -1 (2525 3175)(2525 3225);
WIRE 17 -1 (2525 3125)(2525 3175);
WIRE 17 -1 (2525 3075)(2525 3125);
WIRE 17 -1 (2525 3025)(2525 3075);
WIRE 17 -1 (2525 2975)(2525 3025);
WIRE 17 -1 (2525 2925)(2525 2975);
WIRE 17 -1 (2525 3925)(3525 3925);
FORCEPROP 2 LAST SIG_NAME M_B_CPU1_SA_DQS_DP<9:0>
J 0
(2665 3935);
DISPLAY 0.680851 (2665 3935);
PAINT WHITE (2665 3935);
WIRE 17 -1 (2525 3875)(2525 3925);
WIRE 17 -1 (2525 3825)(2525 3875);
WIRE 17 -1 (2525 3775)(2525 3825);
WIRE 17 -1 (2525 3725)(2525 3775);
WIRE 17 -1 (2525 3675)(2525 3725);
WIRE 17 -1 (2525 3625)(2525 3675);
WIRE 17 -1 (2525 3575)(2525 3625);
WIRE 17 -1 (2525 3525)(2525 3575);
WIRE 17 -1 (2525 3475)(2525 3525);
WIRE 17 -1 (2525 1125)(3525 1125);
FORCEPROP 2 LAST SIG_NAME M_B_CPU1_SB_CA<6:0>
J 0
(2665 1135);
DISPLAY 0.680851 (2665 1135);
PAINT WHITE (2665 1135);
WIRE 17 -1 (2525 1075)(2525 1125);
WIRE 17 -1 (2525 1025)(2525 1075);
WIRE 17 -1 (2525 975)(2525 1025);
WIRE 17 -1 (2525 925)(2525 975);
WIRE 17 -1 (2525 875)(2525 925);
WIRE 17 -1 (2525 825)(2525 875);
WIRE 17 -1 (2525 325)(3525 325);
FORCEPROP 2 LAST SIG_NAME M_B_CPU1_SB_CS_N<3:0>
J 0
(2665 335);
DISPLAY 0.680851 (2665 335);
PAINT WHITE (2665 335);
WIRE 17 -1 (2525 275)(2525 325);
WIRE 17 -1 (2525 225)(2525 275);
WIRE 17 -1 (2525 175)(2525 225);
WIRE 17 -1 (2525 2225)(3525 2225);
FORCEPROP 2 LAST SIG_NAME M_B_CPU1_SB_DQS_DN<9:0>
J 0
(2665 2235);
DISPLAY 0.680851 (2665 2235);
PAINT WHITE (2665 2235);
WIRE 17 -1 (2525 2175)(2525 2225);
WIRE 17 -1 (2525 2125)(2525 2175);
WIRE 17 -1 (2525 2075)(2525 2125);
WIRE 17 -1 (2525 2025)(2525 2075);
WIRE 17 -1 (2525 1975)(2525 2025);
WIRE 17 -1 (2525 1925)(2525 1975);
WIRE 17 -1 (2525 1875)(2525 1925);
WIRE 17 -1 (2525 1825)(2525 1875);
WIRE 17 -1 (2525 1775)(2525 1825);
WIRE 17 -1 (2525 2775)(3525 2775);
FORCEPROP 2 LAST SIG_NAME M_B_CPU1_SB_DQS_DP<9:0>
J 0
(2665 2785);
DISPLAY 0.680851 (2665 2785);
PAINT WHITE (2665 2785);
WIRE 17 -1 (2525 2725)(2525 2775);
WIRE 17 -1 (2525 2675)(2525 2725);
WIRE 17 -1 (2525 2625)(2525 2675);
WIRE 17 -1 (2525 2575)(2525 2625);
WIRE 17 -1 (2525 2525)(2525 2575);
WIRE 17 -1 (2525 2475)(2525 2525);
WIRE 17 -1 (2525 2425)(2525 2475);
WIRE 17 -1 (2525 2375)(2525 2425);
WIRE 17 -1 (2525 2325)(2525 2375);
WIRE 17 -1 (-1000 -25)(-1000 25);
WIRE 17 -1 (-1000 25)(-1000 75);
WIRE 17 -1 (-1000 75)(-1000 125);
WIRE 17 -1 (-1000 125)(-1000 175);
WIRE 17 -1 (-1000 175)(-1000 225);
WIRE 17 -1 (-1000 225)(-1000 275);
WIRE 17 -1 (-1000 275)(-1000 325);
WIRE 17 -1 (-1925 325)(-1000 325);
FORCEPROP 2 LAST SIG_NAME M_B_CPU1_SB_CB<7:0>
J 0
(-1785 335);
DISPLAY 0.680851 (-1785 335);
PAINT WHITE (-1785 335);
WIRE 17 -1 (-1000 375)(-1000 425);
WIRE 17 -1 (-1000 425)(-1000 475);
WIRE 17 -1 (-1000 475)(-1000 525);
WIRE 17 -1 (-1000 525)(-1000 575);
WIRE 17 -1 (-1000 575)(-1000 625);
WIRE 17 -1 (-1000 625)(-1000 675);
WIRE 17 -1 (-1000 675)(-1000 725);
WIRE 17 -1 (-1000 725)(-1000 775);
WIRE 17 -1 (-1000 775)(-1000 825);
WIRE 17 -1 (-1000 825)(-1000 875);
WIRE 17 -1 (-1000 875)(-1000 925);
WIRE 17 -1 (-1000 925)(-1000 975);
WIRE 17 -1 (-1000 975)(-1000 1025);
WIRE 17 -1 (-1000 1025)(-1000 1075);
WIRE 17 -1 (-1000 1075)(-1000 1125);
WIRE 17 -1 (-1000 1125)(-1000 1175);
WIRE 17 -1 (-1000 1175)(-1000 1225);
WIRE 17 -1 (-1000 1225)(-1000 1275);
WIRE 17 -1 (-1000 1275)(-1000 1325);
WIRE 17 -1 (-1000 1325)(-1000 1375);
WIRE 17 -1 (-1000 1375)(-1000 1425);
WIRE 17 -1 (-1000 1425)(-1000 1475);
WIRE 17 -1 (-1000 1475)(-1000 1525);
WIRE 17 -1 (-1000 1525)(-1000 1575);
WIRE 17 -1 (-1000 1575)(-1000 1625);
WIRE 17 -1 (-1000 1625)(-1000 1675);
WIRE 17 -1 (-1000 1675)(-1000 1725);
WIRE 17 -1 (-1000 1725)(-1000 1775);
WIRE 17 -1 (-1000 1775)(-1000 1825);
WIRE 17 -1 (-1000 1825)(-1000 1875);
WIRE 17 -1 (-1000 1875)(-1000 1925);
WIRE 17 -1 (-1925 1925)(-1000 1925);
FORCEPROP 2 LAST SIG_NAME M_B_CPU1_SB_DQ<31:0>
J 0
(-1785 1935);
DISPLAY 0.680851 (-1785 1935);
PAINT WHITE (-1785 1935);
WIRE 17 -1 (-1000 1975)(-1000 2025);
WIRE 17 -1 (-1000 2025)(-1000 2075);
WIRE 17 -1 (-1000 2075)(-1000 2125);
WIRE 17 -1 (-1000 2125)(-1000 2175);
WIRE 17 -1 (-1000 2175)(-1000 2225);
WIRE 17 -1 (-1000 2225)(-1000 2275);
WIRE 17 -1 (-1000 2275)(-1000 2325);
WIRE 17 -1 (-1925 2325)(-1000 2325);
FORCEPROP 2 LAST SIG_NAME M_B_CPU1_SA_CB<7:0>
J 0
(-1785 2335);
DISPLAY 0.680851 (-1785 2335);
PAINT WHITE (-1785 2335);
WIRE 17 -1 (-1000 2375)(-1000 2425);
WIRE 17 -1 (-1000 2425)(-1000 2475);
WIRE 17 -1 (-1000 2475)(-1000 2525);
WIRE 17 -1 (-1000 2525)(-1000 2575);
WIRE 17 -1 (-1000 2575)(-1000 2625);
WIRE 17 -1 (-1000 2625)(-1000 2675);
WIRE 17 -1 (-1000 2675)(-1000 2725);
WIRE 17 -1 (-1000 2725)(-1000 2775);
WIRE 17 -1 (-1000 2775)(-1000 2825);
WIRE 17 -1 (-1000 2825)(-1000 2875);
WIRE 17 -1 (-1000 2875)(-1000 2925);
WIRE 17 -1 (-1000 2925)(-1000 2975);
WIRE 17 -1 (-1000 2975)(-1000 3025);
WIRE 17 -1 (-1000 3025)(-1000 3075);
WIRE 17 -1 (-1000 3075)(-1000 3125);
WIRE 17 -1 (-1000 3125)(-1000 3175);
WIRE 17 -1 (-1000 3175)(-1000 3225);
WIRE 17 -1 (-1000 3225)(-1000 3275);
WIRE 17 -1 (-1000 3275)(-1000 3325);
WIRE 17 -1 (-1000 3325)(-1000 3375);
WIRE 17 -1 (-1000 3375)(-1000 3425);
WIRE 17 -1 (-1000 3425)(-1000 3475);
WIRE 17 -1 (-1000 3475)(-1000 3525);
WIRE 17 -1 (-1000 3525)(-1000 3575);
WIRE 17 -1 (-1000 3575)(-1000 3625);
WIRE 17 -1 (-1000 3625)(-1000 3675);
WIRE 17 -1 (-1000 3675)(-1000 3725);
WIRE 17 -1 (-1000 3725)(-1000 3775);
WIRE 17 -1 (-1000 3775)(-1000 3825);
WIRE 17 -1 (-1000 3825)(-1000 3875);
WIRE 17 -1 (-1000 3875)(-1000 3925);
WIRE 17 -1 (-1925 3925)(-1000 3925);
FORCEPROP 2 LAST SIG_NAME M_B_CPU1_SA_DQ<31:0>
J 0
(-1785 3935);
DISPLAY 0.680851 (-1785 3935);
PAINT WHITE (-1785 3935);
WIRE 17 -1 (-1000 -175)(-1000 -125);
WIRE 17 -1 (-1925 -125)(-1000 -125);
FORCEPROP 2 LAST SIG_NAME M_B_CPU1_CLK_DP<1:0>
J 0
(-1785 -115);
DISPLAY 0.680851 (-1785 -115);
PAINT WHITE (-1785 -115);
WIRE 17 -1 (-1000 -275)(-1000 -225);
WIRE 17 -1 (-1925 -225)(-1000 -225);
FORCEPROP 2 LAST SIG_NAME M_B_CPU1_CLK_DN<1:0>
J 0
(-1785 -215);
DISPLAY 0.680851 (-1785 -215);
PAINT WHITE (-1785 -215);
WIRE 16 -1 (-900 -250)(-450 -250);
WIRE 16 -1 (-900 -300)(-450 -300);
WIRE 16 -1 (-900 -150)(-450 -150);
WIRE 16 -1 (-900 -200)(-450 -200);
WIRE 16 -1 (-900 3900)(-450 3900);
WIRE 16 -1 (-900 3850)(-450 3850);
WIRE 16 -1 (-900 3800)(-450 3800);
WIRE 16 -1 (-900 3750)(-450 3750);
WIRE 16 -1 (-900 3700)(-450 3700);
WIRE 16 -1 (-900 3650)(-450 3650);
WIRE 16 -1 (-900 3600)(-450 3600);
WIRE 16 -1 (-900 3550)(-450 3550);
WIRE 16 -1 (-900 3500)(-450 3500);
WIRE 16 -1 (-900 3450)(-450 3450);
WIRE 16 -1 (-900 3400)(-450 3400);
WIRE 16 -1 (-900 3350)(-450 3350);
WIRE 16 -1 (-900 3300)(-450 3300);
WIRE 16 -1 (-900 3250)(-450 3250);
WIRE 16 -1 (-900 3200)(-450 3200);
WIRE 16 -1 (-900 3150)(-450 3150);
WIRE 16 -1 (-900 3100)(-450 3100);
WIRE 16 -1 (-900 3050)(-450 3050);
WIRE 16 -1 (-900 3000)(-450 3000);
WIRE 16 -1 (-900 2950)(-450 2950);
WIRE 16 -1 (-900 2900)(-450 2900);
WIRE 16 -1 (-900 2850)(-450 2850);
WIRE 16 -1 (-900 2800)(-450 2800);
WIRE 16 -1 (-900 2750)(-450 2750);
WIRE 16 -1 (-900 2700)(-450 2700);
WIRE 16 -1 (-900 2650)(-450 2650);
WIRE 16 -1 (-900 2600)(-450 2600);
WIRE 16 -1 (-900 2550)(-450 2550);
WIRE 16 -1 (-900 2500)(-450 2500);
WIRE 16 -1 (-900 2450)(-450 2450);
WIRE 16 -1 (-900 2400)(-450 2400);
WIRE 16 -1 (-900 2350)(-450 2350);
WIRE 16 -1 (-900 2300)(-450 2300);
WIRE 16 -1 (-900 2250)(-450 2250);
WIRE 16 -1 (-900 2200)(-450 2200);
WIRE 16 -1 (-900 2150)(-450 2150);
WIRE 16 -1 (-900 2100)(-450 2100);
WIRE 16 -1 (-900 2050)(-450 2050);
WIRE 16 -1 (-900 2000)(-450 2000);
WIRE 16 -1 (-900 1950)(-450 1950);
WIRE 16 -1 (-900 1900)(-450 1900);
WIRE 16 -1 (-900 1850)(-450 1850);
WIRE 16 -1 (-900 1800)(-450 1800);
WIRE 16 -1 (-900 1750)(-450 1750);
WIRE 16 -1 (-900 1700)(-450 1700);
WIRE 16 -1 (-900 1650)(-450 1650);
WIRE 16 -1 (-900 1600)(-450 1600);
WIRE 16 -1 (-900 1550)(-450 1550);
WIRE 16 -1 (-900 1500)(-450 1500);
WIRE 16 -1 (-900 1450)(-450 1450);
WIRE 16 -1 (-900 1400)(-450 1400);
WIRE 16 -1 (-900 1350)(-450 1350);
WIRE 16 -1 (-900 1300)(-450 1300);
WIRE 16 -1 (-900 1250)(-450 1250);
WIRE 16 -1 (-900 1200)(-450 1200);
WIRE 16 -1 (-900 1150)(-450 1150);
WIRE 16 -1 (-900 1100)(-450 1100);
WIRE 16 -1 (-900 1050)(-450 1050);
WIRE 16 -1 (-900 1000)(-450 1000);
WIRE 16 -1 (-900 950)(-450 950);
WIRE 16 -1 (-900 900)(-450 900);
WIRE 16 -1 (-900 850)(-450 850);
WIRE 16 -1 (-900 800)(-450 800);
WIRE 16 -1 (-900 750)(-450 750);
WIRE 16 -1 (-900 700)(-450 700);
WIRE 16 -1 (-900 650)(-450 650);
WIRE 16 -1 (-900 600)(-450 600);
WIRE 16 -1 (-900 550)(-450 550);
WIRE 16 -1 (-900 500)(-450 500);
WIRE 16 -1 (-900 450)(-450 450);
WIRE 16 -1 (-900 400)(-450 400);
WIRE 16 -1 (-900 350)(-450 350);
WIRE 16 -1 (-900 300)(-450 300);
WIRE 16 -1 (-900 250)(-450 250);
WIRE 16 -1 (-900 200)(-450 200);
WIRE 16 -1 (-900 150)(-450 150);
WIRE 16 -1 (-900 100)(-450 100);
WIRE 16 -1 (-900 50)(-450 50);
WIRE 16 -1 (-900 0)(-450 0);
WIRE 16 -1 (-900 -50)(-450 -50);
WIRE 16 -1 (3525 750)(2000 750);
FORCEPROP 2 LAST SIG_NAME M_B_CPU1_SB_PAR
J 0
(2634 759);
DISPLAY 0.680851 (2634 759);
PAINT WHITE (2634 759);
WIRE 16 -1 (2000 2300)(2425 2300);
WIRE 16 -1 (2000 2350)(2425 2350);
WIRE 16 -1 (2000 2400)(2425 2400);
WIRE 16 -1 (2000 2450)(2425 2450);
WIRE 16 -1 (2000 2500)(2425 2500);
WIRE 16 -1 (2000 2550)(2425 2550);
WIRE 16 -1 (2000 2600)(2425 2600);
WIRE 16 -1 (2000 2650)(2425 2650);
WIRE 16 -1 (2000 2700)(2425 2700);
WIRE 16 -1 (2000 2750)(2425 2750);
WIRE 16 -1 (2000 1750)(2425 1750);
WIRE 16 -1 (2000 1800)(2425 1800);
WIRE 16 -1 (2000 1850)(2425 1850);
WIRE 16 -1 (2000 1900)(2425 1900);
WIRE 16 -1 (2000 1950)(2425 1950);
WIRE 16 -1 (2000 2000)(2425 2000);
WIRE 16 -1 (2000 2050)(2425 2050);
WIRE 16 -1 (2000 2100)(2425 2100);
WIRE 16 -1 (2000 2150)(2425 2150);
WIRE 16 -1 (2000 2200)(2425 2200);
WIRE 16 -1 (2000 150)(2425 150);
WIRE 16 -1 (2000 200)(2425 200);
WIRE 16 -1 (2000 250)(2425 250);
WIRE 16 -1 (2000 300)(2425 300);
WIRE 16 -1 (2000 800)(2425 800);
WIRE 16 -1 (2000 850)(2425 850);
WIRE 16 -1 (2000 900)(2425 900);
WIRE 16 -1 (2000 950)(2425 950);
WIRE 16 -1 (2000 1000)(2425 1000);
WIRE 16 -1 (2000 1050)(2425 1050);
WIRE 16 -1 (2000 1100)(2425 1100);
WIRE 16 -1 (3525 1250)(2000 1250);
FORCEPROP 2 LAST SIG_NAME M_B_CPU1_SA_PAR
J 0
(2634 1259);
DISPLAY 0.680851 (2634 1259);
PAINT WHITE (2634 1259);
WIRE 16 -1 (2000 3450)(2425 3450);
WIRE 16 -1 (2000 3500)(2425 3500);
WIRE 16 -1 (2000 3550)(2425 3550);
WIRE 16 -1 (2000 3600)(2425 3600);
WIRE 16 -1 (2000 3650)(2425 3650);
WIRE 16 -1 (2000 3700)(2425 3700);
WIRE 16 -1 (2000 3750)(2425 3750);
WIRE 16 -1 (2000 3800)(2425 3800);
WIRE 16 -1 (2000 3850)(2425 3850);
WIRE 16 -1 (2000 3900)(2425 3900);
WIRE 16 -1 (2000 2900)(2425 2900);
WIRE 16 -1 (2000 2950)(2425 2950);
WIRE 16 -1 (2000 3000)(2425 3000);
WIRE 16 -1 (2000 3050)(2425 3050);
WIRE 16 -1 (2000 3100)(2425 3100);
WIRE 16 -1 (2000 3150)(2425 3150);
WIRE 16 -1 (2000 3200)(2425 3200);
WIRE 16 -1 (2000 3250)(2425 3250);
WIRE 16 -1 (2000 3300)(2425 3300);
WIRE 16 -1 (2000 3350)(2425 3350);
WIRE 16 -1 (2000 450)(2425 450);
WIRE 16 -1 (2000 500)(2425 500);
WIRE 16 -1 (2000 550)(2425 550);
WIRE 16 -1 (2000 600)(2425 600);
WIRE 16 -1 (2000 1300)(2425 1300);
WIRE 16 -1 (2000 1350)(2425 1350);
WIRE 16 -1 (2000 1400)(2425 1400);
WIRE 16 -1 (2000 1450)(2425 1450);
WIRE 16 -1 (2000 1500)(2425 1500);
WIRE 16 -1 (2000 1550)(2425 1550);
WIRE 16 -1 (2000 1600)(2425 1600);
WIRE 16 -1 (3525 -200)(2000 -200);
FORCEPROP 2 LAST SIG_NAME M_B_CPU1_SB_RSP<0>
J 0
(2634 -191);
DISPLAY 0.680851 (2634 -191);
PAINT WHITE (2634 -191);
WIRE 16 -1 (3525 -150)(2000 -150);
FORCEPROP 2 LAST SIG_NAME M_B_CPU1_SB_RSP<1>
J 0
(2634 -141);
DISPLAY 0.680851 (2634 -141);
PAINT WHITE (2634 -141);
WIRE 16 -1 (3525 -50)(2000 -50);
FORCEPROP 2 LAST SIG_NAME M_B_CPU1_SA_RSP<0>
J 0
(2634 -41);
DISPLAY 0.680851 (2634 -41);
PAINT WHITE (2634 -41);
WIRE 16 -1 (3525 0)(2000 0);
FORCEPROP 2 LAST SIG_NAME M_B_CPU1_SA_RSP<1>
J 0
(2634 9);
DISPLAY 0.680851 (2634 9);
PAINT WHITE (2634 9);
WIRE 16 -1 (3525 -300)(2000 -300);
FORCEPROP 2 LAST SIG_NAME M_B_CPU1_ALERT_N
J 0
(2634 -291);
DISPLAY 0.680851 (2634 -291);
PAINT WHITE (2634 -291);
QUIT
